FILE_TYPE = MACRO_DRAWING;
SET COLOR_WIRE YELLOW;
SET COLOR_PROP ORANGE;
SET COLOR_DOT WHITE;
SET COLOR_ARC YELLOW;
SET COLOR_BODY GREEN;
SET COLOR_NOTE PURPLE;
SET PROP_DISPLAY VALUE;
SET PAGE_NUMBER P28;
SET PATH_NUMBER P185;
FORCEADD UNIVERSAL_GND..1
R 2
(200 1825);
FORCEPROP 3 LASTPIN (200 1875) SIG_NAME GND\g
J 0
(210 1885);
DISPLAY 0.659574 (210 1885);
PAINT MONO (210 1885);
DISPLAY INVISIBLE (210 1885);
FORCEPROP 1 LAST HDL_POWER GND
J 1
(175 1750);
DISPLAY 0.702128 (175 1750);
PAINT GREEN (175 1750);
FORCEPROP 2 LAST CDS_LIB logical_power
J 2
(200 1825);
DISPLAY INVISIBLE (200 1825);
FORCEPROP 1 LAST PATH I100
J 2
(125 1825);
DISPLAY 0.872340 (125 1825);
PAINT AQUA (125 1825);
DISPLAY INVISIBLE (125 1825);
FORCEADD Q_CAP..1
R 2
(-75 2825);
FORCEPROP 1 LAST MATERIAL X7R
J 2
(-125 2725);
DISPLAY 0.978723 (-125 2725);
FORCEPROP 1 LAST VALUE 0.1UF
J 2
(-125 2875);
DISPLAY 0.978723 (-125 2875);
FORCEPROP 1 LAST VOLTAGE 25V
J 2
(-125 2825);
DISPLAY 0.978723 (-125 2825);
FORCEPROP 1 LAST PACK_TYPE 0402
J 2
(-125 2625);
DISPLAY 0.978723 (-125 2625);
FORCEPROP 1 LAST TOLERANCE 10%
J 2
(-125 2775);
DISPLAY 0.978723 (-125 2775);
FORCEPROP 1 LAST PART_NUMBER CH4104K1B00
J 2
(-125 2675);
DISPLAY 0.978723 (-125 2675);
FORCEPROP 2 LAST CDS_LIB pure_quanta
J 2
(-75 2825);
DISPLAY INVISIBLE (-75 2825);
FORCEPROP 1 LAST PATH I101
J 2
(-125 2975);
DISPLAY 0.978723 (-125 2975);
PAINT WHITE (-125 2975);
DISPLAY INVISIBLE (-125 2975);
FORCEPROP 1 LAST LOCATION C158
J 2
(-125 2925);
DISPLAY 0.978723 (-125 2925);
FORCEPROP 1 LASTPIN (-75 2925) $PN 1
J 2
(-85 2905);
DISPLAY 0.787234 (-85 2905);
PAINT MONO (-85 2905);
FORCEPROP 1 LASTPIN (-75 2725) $PN 2
J 2
(-85 2705);
DISPLAY 0.787234 (-85 2705);
PAINT MONO (-85 2705);
FORCEPROP 2 LAST $SEC 1
J 0
(-125 3025);
DISPLAY 0.680851 (-125 3025);
PAINT MONO (-125 3025);
DISPLAY INVISIBLE (-125 3025);
FORCEPROP 2 LAST CDS_SEC 1
J 0
(-125 3025);
DISPLAY 1.021277 (-125 3025);
DISPLAY INVISIBLE (-125 3025);
FORCEADD UNIVERSAL_GND..1
(-75 2550);
FORCEPROP 3 LASTPIN (-75 2600) SIG_NAME GND\g
J 0
(-65 2610);
DISPLAY 0.659574 (-65 2610);
PAINT MONO (-65 2610);
DISPLAY INVISIBLE (-65 2610);
FORCEPROP 1 LAST HDL_POWER GND
J 1
(-50 2475);
DISPLAY 0.702128 (-50 2475);
PAINT GREEN (-50 2475);
FORCEPROP 2 LAST CDS_LIB logical_power
J 0
(-75 2550);
DISPLAY INVISIBLE (-75 2550);
FORCEPROP 1 LAST PATH I102
J 0
(0 2550);
DISPLAY 0.872340 (0 2550);
PAINT AQUA (0 2550);
DISPLAY INVISIBLE (0 2550);
FORCEADD OFFPAGE..5
R 2
(950 3375);
FORCEPROP 2 LAST $XR0 28 
J 0
(1139 3375);
DISPLAY 0.638298 (1139 3375);
PAINT MONO (1139 3375);
FORCEPROP 2 LAST CDS_LIB standard
J 2
(950 3375);
PAINT MONO (950 3375);
DISPLAY INVISIBLE (950 3375);
FORCEPROP 1 LAST OFFPAGE TRUE
J 2
(625 3250);
DISPLAY 0.872340 (625 3250);
PAINT GREEN (625 3250);
DISPLAY INVISIBLE (625 3250);
FORCEPROP 1 LAST COMMENT_BODY TRUE
J 2
(850 3300);
DISPLAY 0.872340 (850 3300);
PAINT PEACH (850 3300);
DISPLAY INVISIBLE (850 3300);
FORCEPROP 2 LAST PATH I103
J 0
(1150 3425);
DISPLAY 0.680851 (1150 3425);
DISPLAY INVISIBLE (1150 3425);
FORCEADD Q_RES..1
(-150 3375);
FORCEPROP 1 LAST WATTAGE 1/16W
J 2
(-175 3275);
DISPLAY 0.510638 (-175 3275);
PAINT SKYBLUE (-175 3275);
FORCEPROP 1 LAST MATERIAL CHIP
J 0
(-150 3275);
DISPLAY 0.510638 (-150 3275);
PAINT SKYBLUE (-150 3275);
FORCEPROP 1 LAST TOLERANCE 5%
J 0
(-150 3325);
DISPLAY 0.510638 (-150 3325);
PAINT SKYBLUE (-150 3325);
FORCEPROP 1 LAST VALUE 0
J 2
(-175 3325);
DISPLAY 0.510638 (-175 3325);
PAINT SKYBLUE (-175 3325);
FORCEPROP 1 LAST PART_NUMBER CS00002JB13
J 0
(-200 3475);
DISPLAY 0.510638 (-200 3475);
PAINT WHITE (-200 3475);
FORCEPROP 1 LAST PACK_TYPE 0402LF
J 0
(50 3275);
DISPLAY 0.510638 (50 3275);
PAINT SKYBLUE (50 3275);
FORCEPROP 2 LAST CDS_LIB pure_quanta
J 0
(-150 3375);
DISPLAY INVISIBLE (-150 3375);
FORCEPROP 1 LAST PATH I104
J 0
(-200 3525);
DISPLAY 0.978723 (-200 3525);
PAINT WHITE (-200 3525);
DISPLAY INVISIBLE (-200 3525);
FORCEPROP 1 LAST LOCATION R670
J 0
(-200 3425);
DISPLAY 0.702128 (-200 3425);
PAINT YELLOW (-200 3425);
FORCEPROP 0 LAST $SEC 1
J 0
(-200 3500);
DISPLAY 0.680851 (-200 3500);
PAINT MONO (-200 3500);
DISPLAY INVISIBLE (-200 3500);
FORCEPROP 0 LAST CDS_SEC 1
J 0
(-200 3500);
DISPLAY 1.021277 (-200 3500);
DISPLAY INVISIBLE (-200 3500);
FORCEPROP 1 LASTPIN (-250 3375) $PN 1
J 0
(-238 3387);
DISPLAY 0.808511 (-238 3387);
PAINT WHITE (-238 3387);
DISPLAY INVISIBLE (-238 3387);
FORCEPROP 1 LASTPIN (-50 3375) $PN 2
J 0
(-88 3387);
DISPLAY 0.808511 (-88 3387);
PAINT WHITE (-88 3387);
DISPLAY INVISIBLE (-88 3387);
FORCEADD Q_RES..2
R 2
(-950 3075);
FORCEPROP 1 LAST MATERIAL EMPTY
J 2
(-990 3000);
DISPLAY 0.978723 (-990 3000);
FORCEPROP 1 LAST WATTAGE 1/16W
J 2
(-990 3050);
DISPLAY 0.978723 (-990 3050);
FORCEPROP 1 LAST PACK_TYPE 0402LF
J 2
(-990 2900);
DISPLAY 0.978723 (-990 2900);
FORCEPROP 1 LAST VALUE 100K
J 2
(-995 3150);
DISPLAY 0.978723 (-995 3150);
FORCEPROP 1 LAST PART_NUMBER CS41002FB09
J 2
(-990 2950);
DISPLAY 0.978723 (-990 2950);
FORCEPROP 1 LAST TOLERANCE 1%
J 2
(-995 3100);
DISPLAY 0.978723 (-995 3100);
FORCEPROP 2 LAST CDS_LIB pure_quanta
J 2
(-950 3075);
DISPLAY INVISIBLE (-950 3075);
FORCEPROP 1 LAST PATH I105
J 2
(-1000 3250);
DISPLAY 0.978723 (-1000 3250);
PAINT WHITE (-1000 3250);
DISPLAY INVISIBLE (-1000 3250);
FORCEPROP 1 LAST LOCATION R296
J 2
(-995 3200);
DISPLAY 0.978723 (-995 3200);
FORCEPROP 1 LASTPIN (-950 3175) $PN 1
J 2
(-955 3137);
DISPLAY 0.787234 (-955 3137);
PAINT MONO (-955 3137);
FORCEPROP 1 LASTPIN (-950 2975) $PN 2
J 2
(-955 2985);
DISPLAY 0.787234 (-955 2985);
PAINT MONO (-955 2985);
FORCEPROP 2 LAST $SEC 1
J 0
(-1000 3300);
DISPLAY 0.680851 (-1000 3300);
PAINT MONO (-1000 3300);
DISPLAY INVISIBLE (-1000 3300);
FORCEPROP 2 LAST CDS_SEC 1
J 0
(-1000 3300);
DISPLAY 1.021277 (-1000 3300);
DISPLAY INVISIBLE (-1000 3300);
FORCEADD UNIVERSAL_GND..1
R 2
(-950 2725);
FORCEPROP 3 LASTPIN (-950 2775) SIG_NAME GND\g
J 0
(-940 2785);
DISPLAY 0.659574 (-940 2785);
PAINT MONO (-940 2785);
DISPLAY INVISIBLE (-940 2785);
FORCEPROP 1 LAST HDL_POWER GND
J 1
(-975 2675);
DISPLAY 0.702128 (-975 2675);
PAINT GREEN (-975 2675);
FORCEPROP 1 LAST PATH I106
J 2
(-1025 2725);
DISPLAY 0.872340 (-1025 2725);
PAINT AQUA (-1025 2725);
DISPLAY INVISIBLE (-1025 2725);
FORCEPROP 2 LAST CDS_LIB logical_power
J 2
(-950 2725);
DISPLAY INVISIBLE (-950 2725);
FORCEADD UNIVERSAL_POWER..1
(-1350 4025);
FORCEPROP 3 LASTPIN (-1350 3975) SIG_NAME P3V3_AUX\g
J 0
(-1340 3985);
DISPLAY 0.659574 (-1340 3985);
PAINT MONO (-1340 3985);
DISPLAY INVISIBLE (-1340 3985);
FORCEPROP 1 LAST HDL_POWER P3V3_AUX
J 1
(-1350 4075);
DISPLAY 0.702128 (-1350 4075);
PAINT PEACH (-1350 4075);
FORCEPROP 1 LAST PATH I107
J 0
(-1300 4050);
DISPLAY 0.872340 (-1300 4050);
PAINT AQUA (-1300 4050);
DISPLAY INVISIBLE (-1300 4050);
FORCEPROP 2 LAST CDS_LIB logical_power
J 0
(-1350 4025);
DISPLAY INVISIBLE (-1350 4025);
FORCEADD Q_RES..1
(-1125 2125);
FORCEPROP 1 LAST VALUE 0
J 2
(-900 2125);
DISPLAY 0.510638 (-900 2125);
PAINT SKYBLUE (-900 2125);
FORCEPROP 1 LAST MATERIAL CHIP
J 0
(-875 2125);
DISPLAY 0.510638 (-875 2125);
PAINT SKYBLUE (-875 2125);
FORCEPROP 2 LAST CDS_LIB pure_quanta
J 0
(-1125 2125);
DISPLAY INVISIBLE (-1125 2125);
FORCEPROP 1 LAST TOLERANCE 5%
J 0
(-1125 2025);
DISPLAY 0.510638 (-1125 2025);
PAINT SKYBLUE (-1125 2025);
DISPLAY INVISIBLE (-1125 2025);
FORCEPROP 1 LAST PATH I108
J 0
(-1175 2275);
DISPLAY 0.978723 (-1175 2275);
PAINT WHITE (-1175 2275);
DISPLAY INVISIBLE (-1175 2275);
FORCEPROP 1 LAST WATTAGE 1/16W
J 2
(-1150 1975);
DISPLAY 0.510638 (-1150 1975);
PAINT SKYBLUE (-1150 1975);
DISPLAY INVISIBLE (-1150 1975);
FORCEPROP 1 LAST PACK_TYPE 0402LF
J 0
(-875 1975);
DISPLAY 0.510638 (-875 1975);
PAINT SKYBLUE (-875 1975);
DISPLAY INVISIBLE (-875 1975);
FORCEPROP 1 LAST PART_NUMBER CS00002JB13
J 0
(-1225 2175);
DISPLAY 0.510638 (-1225 2175);
PAINT WHITE (-1225 2175);
DISPLAY INVISIBLE (-1225 2175);
FORCEPROP 1 LAST LOCATION R294
J 0
(-1375 2125);
DISPLAY 0.702128 (-1375 2125);
PAINT YELLOW (-1375 2125);
FORCEPROP 1 LASTPIN (-1225 2125) $PN 1
J 0
(-1213 2137);
DISPLAY 0.808511 (-1213 2137);
PAINT WHITE (-1213 2137);
FORCEPROP 1 LASTPIN (-1025 2125) $PN 2
J 0
(-1063 2137);
DISPLAY 0.808511 (-1063 2137);
PAINT WHITE (-1063 2137);
FORCEPROP 2 LAST $SEC 1
J 0
(-1250 2350);
DISPLAY 0.680851 (-1250 2350);
PAINT MONO (-1250 2350);
DISPLAY INVISIBLE (-1250 2350);
FORCEPROP 0 LAST CDS_SEC 1
J 0
(-1250 2350);
DISPLAY 0.680851 (-1250 2350);
PAINT MONO (-1250 2350);
DISPLAY INVISIBLE (-1250 2350);
FORCEADD Q_RES..1
(-1125 2225);
FORCEPROP 1 LAST MATERIAL CHIP
J 0
(-875 2225);
DISPLAY 0.510638 (-875 2225);
PAINT SKYBLUE (-875 2225);
FORCEPROP 1 LAST PART_NUMBER CS00002JB13
J 0
(-1225 2275);
DISPLAY 0.510638 (-1225 2275);
PAINT WHITE (-1225 2275);
FORCEPROP 1 LAST VALUE 0
J 2
(-900 2225);
DISPLAY 0.510638 (-900 2225);
PAINT SKYBLUE (-900 2225);
FORCEPROP 2 LAST CDS_LIB pure_quanta
J 0
(-1125 2225);
DISPLAY INVISIBLE (-1125 2225);
FORCEPROP 1 LAST TOLERANCE 5%
J 0
(-1125 2125);
DISPLAY 0.510638 (-1125 2125);
PAINT SKYBLUE (-1125 2125);
DISPLAY INVISIBLE (-1125 2125);
FORCEPROP 1 LAST PATH I109
J 0
(-1175 2375);
DISPLAY 0.978723 (-1175 2375);
PAINT WHITE (-1175 2375);
DISPLAY INVISIBLE (-1175 2375);
FORCEPROP 1 LAST WATTAGE 1/16W
J 2
(-1150 2075);
DISPLAY 0.510638 (-1150 2075);
PAINT SKYBLUE (-1150 2075);
DISPLAY INVISIBLE (-1150 2075);
FORCEPROP 1 LAST PACK_TYPE 0402LF
J 0
(-875 2075);
DISPLAY 0.510638 (-875 2075);
PAINT SKYBLUE (-875 2075);
DISPLAY INVISIBLE (-875 2075);
FORCEPROP 1 LAST LOCATION R135
J 0
(-1375 2225);
DISPLAY 0.702128 (-1375 2225);
PAINT YELLOW (-1375 2225);
FORCEPROP 1 LASTPIN (-1225 2225) $PN 1
J 0
(-1213 2237);
DISPLAY 0.808511 (-1213 2237);
PAINT WHITE (-1213 2237);
FORCEPROP 1 LASTPIN (-1025 2225) $PN 2
J 0
(-1063 2237);
DISPLAY 0.808511 (-1063 2237);
PAINT WHITE (-1063 2237);
FORCEPROP 2 LAST $SEC 1
J 0
(-1250 2450);
DISPLAY 0.680851 (-1250 2450);
PAINT MONO (-1250 2450);
DISPLAY INVISIBLE (-1250 2450);
FORCEPROP 0 LAST CDS_SEC 1
J 0
(-1250 2450);
DISPLAY 0.680851 (-1250 2450);
PAINT MONO (-1250 2450);
DISPLAY INVISIBLE (-1250 2450);
FORCEADD VCCAUX15..1
(-2125 4075);
FORCEPROP 3 LASTPIN (-2125 4025) SIG_NAME P3V3_AUX\g
J 0
(-2115 4035);
DISPLAY 0.659574 (-2115 4035);
PAINT MONO (-2115 4035);
DISPLAY INVISIBLE (-2115 4035);
FORCEPROP 1 LAST HDL_POWER P3V3_AUX
J 1
(-2125 4125);
DISPLAY 0.702128 (-2125 4125);
PAINT GREEN (-2125 4125);
FORCEPROP 1 LAST PATH I110
J 0
(-2075 4100);
DISPLAY 0.872340 (-2075 4100);
PAINT AQUA (-2075 4100);
DISPLAY INVISIBLE (-2075 4100);
FORCEPROP 2 LAST CDS_LIB logical_power
J 0
(-2125 4075);
DISPLAY INVISIBLE (-2125 4075);
FORCEADD Q_RES..2
(-1350 3800);
FORCEPROP 1 LAST PART_NUMBER CS31002FB08
J 0
(-1310 3675);
DISPLAY 0.510638 (-1310 3675);
PAINT WHITE (-1310 3675);
FORCEPROP 1 LAST PACK_TYPE 0402LF
J 0
(-1310 3625);
DISPLAY 0.510638 (-1310 3625);
PAINT SKYBLUE (-1310 3625);
FORCEPROP 1 LAST TOLERANCE 1%
J 0
(-1305 3825);
DISPLAY 0.510638 (-1305 3825);
PAINT SKYBLUE (-1305 3825);
FORCEPROP 1 LAST WATTAGE 1/16W
J 0
(-1310 3775);
DISPLAY 0.510638 (-1310 3775);
PAINT SKYBLUE (-1310 3775);
FORCEPROP 1 LAST MATERIAL CHIP
J 0
(-1310 3725);
DISPLAY 0.510638 (-1310 3725);
PAINT SKYBLUE (-1310 3725);
FORCEPROP 1 LAST VALUE 10K
J 0
(-1305 3875);
DISPLAY 0.510638 (-1305 3875);
PAINT SKYBLUE (-1305 3875);
FORCEPROP 1 LAST PATH I113
J 0
(-1300 3975);
DISPLAY 0.978723 (-1300 3975);
PAINT WHITE (-1300 3975);
DISPLAY INVISIBLE (-1300 3975);
FORCEPROP 2 LAST CDS_LIB pure_quanta
J 0
(-1350 3800);
DISPLAY INVISIBLE (-1350 3800);
FORCEPROP 1 LAST LOCATION R295
J 0
(-1305 3925);
DISPLAY 0.702128 (-1305 3925);
PAINT YELLOW (-1305 3925);
FORCEPROP 0 LAST $SEC 1
J 0
(-1300 3975);
DISPLAY 0.680851 (-1300 3975);
PAINT MONO (-1300 3975);
DISPLAY INVISIBLE (-1300 3975);
FORCEPROP 0 LAST CDS_SEC 1
J 0
(-1300 3975);
DISPLAY 1.021277 (-1300 3975);
DISPLAY INVISIBLE (-1300 3975);
FORCEPROP 1 LASTPIN (-1350 3900) $PN 1
J 0
(-1345 3862);
DISPLAY 0.808511 (-1345 3862);
PAINT WHITE (-1345 3862);
DISPLAY INVISIBLE (-1345 3862);
FORCEPROP 1 LASTPIN (-1350 3700) $PN 2
J 0
(-1345 3710);
DISPLAY 0.808511 (-1345 3710);
PAINT WHITE (-1345 3710);
DISPLAY INVISIBLE (-1345 3710);
FORCEADD UNIVERSAL_GND..1
R 2
(-2900 3100);
FORCEPROP 3 LASTPIN (-2900 3150) SIG_NAME GND\g
J 0
(-2890 3160);
DISPLAY 0.659574 (-2890 3160);
PAINT MONO (-2890 3160);
DISPLAY INVISIBLE (-2890 3160);
FORCEPROP 1 LAST HDL_POWER GND
J 1
(-2925 3025);
DISPLAY 0.702128 (-2925 3025);
PAINT GREEN (-2925 3025);
FORCEPROP 2 LAST CDS_LIB logical_power
J 2
(-2900 3100);
DISPLAY INVISIBLE (-2900 3100);
FORCEPROP 1 LAST PATH I115
J 2
(-2975 3100);
DISPLAY 0.872340 (-2975 3100);
PAINT AQUA (-2975 3100);
DISPLAY INVISIBLE (-2975 3100);
FORCEADD OFFPAGE..5
(-2300 2225);
FORCEPROP 2 LAST $XR1 27 
J 0
(-2614 2225);
DISPLAY 0.638298 (-2614 2225);
PAINT MONO (-2614 2225);
FORCEPROP 2 LAST $XR0 12 
J 0
(-2524 2225);
DISPLAY 0.638298 (-2524 2225);
PAINT MONO (-2524 2225);
FORCEPROP 2 LAST CDS_LIB standard
J 0
(-2300 2225);
DISPLAY INVISIBLE (-2300 2225);
FORCEPROP 1 LAST OFFPAGE TRUE
J 0
(-1975 2100);
DISPLAY 0.872340 (-1975 2100);
DISPLAY INVISIBLE (-1975 2100);
FORCEPROP 1 LAST COMMENT_BODY TRUE
J 0
(-2200 2150);
DISPLAY 0.872340 (-2200 2150);
PAINT GREEN (-2200 2150);
DISPLAY INVISIBLE (-2200 2150);
FORCEPROP 2 LAST PATH I116
J 0
(-2550 2275);
DISPLAY 0.680851 (-2550 2275);
DISPLAY INVISIBLE (-2550 2275);
FORCEADD OFFPAGE..6
(-2300 2125);
FORCEPROP 2 LAST $XR1 27 
J 0
(-2639 2125);
DISPLAY 0.638298 (-2639 2125);
PAINT MONO (-2639 2125);
FORCEPROP 2 LAST $XR0 12 
J 0
(-2549 2125);
DISPLAY 0.638298 (-2549 2125);
PAINT MONO (-2549 2125);
FORCEPROP 2 LAST CDS_LIB standard
J 0
(-2300 2125);
DISPLAY INVISIBLE (-2300 2125);
FORCEPROP 1 LAST OFFPAGE TRUE
J 0
(-1975 2000);
DISPLAY 0.872340 (-1975 2000);
DISPLAY INVISIBLE (-1975 2000);
FORCEPROP 1 LAST COMMENT_BODY TRUE
J 0
(-2200 2050);
DISPLAY 0.872340 (-2200 2050);
PAINT GREEN (-2200 2050);
DISPLAY INVISIBLE (-2200 2050);
FORCEPROP 2 LAST PATH I117
J 0
(-2525 2175);
DISPLAY 0.680851 (-2525 2175);
DISPLAY INVISIBLE (-2525 2175);
FORCEADD OFFPAGE..1
(-3800 3475);
FORCEPROP 2 LAST $XR0 29 
J 0
(-4021 3475);
DISPLAY 0.638298 (-4021 3475);
PAINT MONO (-4021 3475);
FORCEPROP 2 LAST CDS_LIB standard
J 0
(-3800 3475);
DISPLAY INVISIBLE (-3800 3475);
FORCEPROP 1 LAST OFFPAGE TRUE
J 0
(-3475 3350);
DISPLAY 0.872340 (-3475 3350);
PAINT GREEN (-3475 3350);
DISPLAY INVISIBLE (-3475 3350);
FORCEPROP 1 LAST COMMENT_BODY TRUE
J 0
(-3675 3375);
DISPLAY 0.872340 (-3675 3375);
PAINT PEACH (-3675 3375);
DISPLAY INVISIBLE (-3675 3375);
FORCEPROP 2 LAST PATH I118
J 0
(-4050 3525);
DISPLAY 0.680851 (-4050 3525);
DISPLAY INVISIBLE (-4050 3525);
FORCEADD OFFPAGE..4
(3625 -1125);
FORCEPROP 2 LAST $XR3 35 
J 0
(4081 -1125);
DISPLAY 0.638298 (4081 -1125);
PAINT MONO (4081 -1125);
FORCEPROP 2 LAST $XR2 13 
J 0
(3991 -1125);
DISPLAY 0.638298 (3991 -1125);
PAINT MONO (3991 -1125);
FORCEPROP 2 LAST $XR0 10 
J 0
(3811 -1125);
DISPLAY 0.638298 (3811 -1125);
PAINT MONO (3811 -1125);
FORCEPROP 2 LAST $XR1 11 
J 0
(3901 -1125);
DISPLAY 0.638298 (3901 -1125);
PAINT MONO (3901 -1125);
FORCEPROP 2 LAST CDS_LIB standard
J 0
(3625 -1125);
DISPLAY INVISIBLE (3625 -1125);
FORCEPROP 1 LAST OFFPAGE TRUE
J 0
(3950 -1250);
DISPLAY 0.872340 (3950 -1250);
DISPLAY INVISIBLE (3950 -1250);
FORCEPROP 1 LAST COMMENT_BODY TRUE
J 0
(3600 -1225);
DISPLAY 0.872340 (3600 -1225);
PAINT GREEN (3600 -1225);
DISPLAY INVISIBLE (3600 -1225);
FORCEPROP 2 LAST PATH I121
J 0
(4100 -1075);
DISPLAY 0.680851 (4100 -1075);
DISPLAY INVISIBLE (4100 -1075);
FORCEADD OFFPAGE..4
(3625 -1175);
FORCEPROP 2 LAST $XR4 46 
J 0
(4171 -1175);
DISPLAY 0.638298 (4171 -1175);
PAINT MONO (4171 -1175);
FORCEPROP 2 LAST $XR3 34 
J 0
(4081 -1175);
DISPLAY 0.638298 (4081 -1175);
PAINT MONO (4081 -1175);
FORCEPROP 2 LAST $XR2 12 
J 0
(3991 -1175);
DISPLAY 0.638298 (3991 -1175);
PAINT MONO (3991 -1175);
FORCEPROP 2 LAST $XR1 11 
J 0
(3901 -1175);
DISPLAY 0.638298 (3901 -1175);
PAINT MONO (3901 -1175);
FORCEPROP 2 LAST $XR0 10 
J 0
(3811 -1175);
DISPLAY 0.638298 (3811 -1175);
PAINT MONO (3811 -1175);
FORCEPROP 2 LAST CDS_LIB standard
J 0
(3625 -1175);
DISPLAY INVISIBLE (3625 -1175);
FORCEPROP 1 LAST OFFPAGE TRUE
J 0
(3950 -1300);
DISPLAY 0.872340 (3950 -1300);
DISPLAY INVISIBLE (3950 -1300);
FORCEPROP 1 LAST COMMENT_BODY TRUE
J 0
(3600 -1275);
DISPLAY 0.872340 (3600 -1275);
PAINT GREEN (3600 -1275);
DISPLAY INVISIBLE (3600 -1275);
FORCEPROP 2 LAST PATH I122
J 0
(4175 -1125);
DISPLAY 0.680851 (4175 -1125);
DISPLAY INVISIBLE (4175 -1125);
FORCEADD OFFPAGE..4
(3625 -1225);
FORCEPROP 2 LAST $XR2 13 
J 0
(3991 -1225);
DISPLAY 0.638298 (3991 -1225);
PAINT MONO (3991 -1225);
FORCEPROP 2 LAST $XR1 42 
J 0
(3901 -1225);
DISPLAY 0.638298 (3901 -1225);
PAINT MONO (3901 -1225);
FORCEPROP 2 LAST $XR0 36 
J 0
(3811 -1225);
DISPLAY 0.638298 (3811 -1225);
PAINT MONO (3811 -1225);
FORCEPROP 2 LAST CDS_LIB standard
J 0
(3625 -1225);
DISPLAY INVISIBLE (3625 -1225);
FORCEPROP 1 LAST OFFPAGE TRUE
J 0
(3950 -1350);
DISPLAY 0.872340 (3950 -1350);
DISPLAY INVISIBLE (3950 -1350);
FORCEPROP 1 LAST COMMENT_BODY TRUE
J 0
(3600 -1325);
DISPLAY 0.872340 (3600 -1325);
PAINT GREEN (3600 -1325);
DISPLAY INVISIBLE (3600 -1325);
FORCEPROP 2 LAST PATH I123
J 0
(3925 -1175);
DISPLAY 0.680851 (3925 -1175);
DISPLAY INVISIBLE (3925 -1175);
FORCEADD OFFPAGE..4
(3625 -1300);
FORCEPROP 2 LAST $XR4 34 
J 0
(4171 -1300);
DISPLAY 0.638298 (4171 -1300);
PAINT MONO (4171 -1300);
FORCEPROP 2 LAST $XR3 22 
J 0
(4081 -1300);
DISPLAY 0.638298 (4081 -1300);
PAINT MONO (4081 -1300);
FORCEPROP 2 LAST $XR2 13 
J 0
(3991 -1300);
DISPLAY 0.638298 (3991 -1300);
PAINT MONO (3991 -1300);
FORCEPROP 2 LAST $XR1 11 
J 0
(3901 -1300);
DISPLAY 0.638298 (3901 -1300);
PAINT MONO (3901 -1300);
FORCEPROP 2 LAST $XR0 10 
J 0
(3811 -1300);
DISPLAY 0.638298 (3811 -1300);
PAINT MONO (3811 -1300);
FORCEPROP 2 LAST CDS_LIB standard
J 0
(3625 -1300);
DISPLAY INVISIBLE (3625 -1300);
FORCEPROP 1 LAST OFFPAGE TRUE
J 0
(3950 -1425);
DISPLAY 0.872340 (3950 -1425);
DISPLAY INVISIBLE (3950 -1425);
FORCEPROP 1 LAST COMMENT_BODY TRUE
J 0
(3600 -1400);
DISPLAY 0.872340 (3600 -1400);
PAINT GREEN (3600 -1400);
DISPLAY INVISIBLE (3600 -1400);
FORCEPROP 2 LAST PATH I124
J 0
(4175 -1250);
DISPLAY 0.680851 (4175 -1250);
DISPLAY INVISIBLE (4175 -1250);
FORCEADD Q_RES..1
R 2
(2000 -1125);
FORCEPROP 1 LAST VALUE 0
J 0
(2050 -1150);
DISPLAY 0.510638 (2050 -1150);
PAINT SKYBLUE (2050 -1150);
FORCEPROP 1 LAST TOLERANCE 5%
J 2
(2150 -1150);
DISPLAY 0.510638 (2150 -1150);
PAINT SKYBLUE (2150 -1150);
FORCEPROP 1 LAST PACK_TYPE 0402LF
J 2
(2600 -1150);
DISPLAY 0.510638 (2600 -1150);
PAINT SKYBLUE (2600 -1150);
FORCEPROP 1 LAST MATERIAL CHIP
J 2
(2275 -1150);
DISPLAY 0.510638 (2275 -1150);
PAINT SKYBLUE (2275 -1150);
FORCEPROP 1 LAST WATTAGE 1/16W
J 0
(2300 -1150);
DISPLAY 0.510638 (2300 -1150);
PAINT SKYBLUE (2300 -1150);
FORCEPROP 2 LAST CDS_LIB pure_quanta
J 0
(2000 -1125);
DISPLAY INVISIBLE (2000 -1125);
FORCEPROP 1 LAST PATH I125
J 2
(2050 -975);
DISPLAY 0.978723 (2050 -975);
PAINT WHITE (2050 -975);
DISPLAY INVISIBLE (2050 -975);
FORCEPROP 1 LAST PART_NUMBER CS00002JB13
J 2
(2250 -1100);
DISPLAY 0.510638 (2250 -1100);
PAINT WHITE (2250 -1100);
DISPLAY INVISIBLE (2250 -1100);
FORCEPROP 1 LAST LOCATION R701
J 2
(1875 -1125);
DISPLAY 0.702128 (1875 -1125);
PAINT YELLOW (1875 -1125);
FORCEPROP 0 LAST $SEC 1
J 0
(1950 -1075);
DISPLAY 0.680851 (1950 -1075);
PAINT MONO (1950 -1075);
DISPLAY INVISIBLE (1950 -1075);
FORCEPROP 0 LAST CDS_SEC 1
J 0
(1950 -1075);
DISPLAY 1.021277 (1950 -1075);
DISPLAY INVISIBLE (1950 -1075);
FORCEPROP 1 LASTPIN (2100 -1125) $PN 1
J 2
(2088 -1113);
DISPLAY 0.808511 (2088 -1113);
PAINT WHITE (2088 -1113);
DISPLAY INVISIBLE (2088 -1113);
FORCEPROP 1 LASTPIN (1900 -1125) $PN 2
J 2
(1938 -1113);
DISPLAY 0.808511 (1938 -1113);
PAINT WHITE (1938 -1113);
DISPLAY INVISIBLE (1938 -1113);
FORCEADD Q_RES..1
R 2
(2000 -1175);
FORCEPROP 1 LAST VALUE 0
J 0
(2050 -1200);
DISPLAY 0.510638 (2050 -1200);
PAINT SKYBLUE (2050 -1200);
FORCEPROP 1 LAST TOLERANCE 5%
J 2
(2150 -1200);
DISPLAY 0.510638 (2150 -1200);
PAINT SKYBLUE (2150 -1200);
FORCEPROP 1 LAST PACK_TYPE 0402LF
J 2
(2600 -1200);
DISPLAY 0.510638 (2600 -1200);
PAINT SKYBLUE (2600 -1200);
FORCEPROP 1 LAST MATERIAL CHIP
J 2
(2275 -1200);
DISPLAY 0.510638 (2275 -1200);
PAINT SKYBLUE (2275 -1200);
FORCEPROP 1 LAST WATTAGE 1/16W
J 0
(2300 -1200);
DISPLAY 0.510638 (2300 -1200);
PAINT SKYBLUE (2300 -1200);
FORCEPROP 2 LAST CDS_LIB pure_quanta
J 0
(2000 -1175);
DISPLAY INVISIBLE (2000 -1175);
FORCEPROP 1 LAST PATH I126
J 2
(2050 -1025);
DISPLAY 0.978723 (2050 -1025);
PAINT WHITE (2050 -1025);
DISPLAY INVISIBLE (2050 -1025);
FORCEPROP 1 LAST PART_NUMBER CS00002JB13
J 2
(2250 -1150);
DISPLAY 0.510638 (2250 -1150);
PAINT WHITE (2250 -1150);
DISPLAY INVISIBLE (2250 -1150);
FORCEPROP 1 LAST LOCATION R702
J 2
(1875 -1175);
DISPLAY 0.702128 (1875 -1175);
PAINT YELLOW (1875 -1175);
FORCEPROP 0 LAST $SEC 1
J 0
(1950 -1125);
DISPLAY 0.680851 (1950 -1125);
PAINT MONO (1950 -1125);
DISPLAY INVISIBLE (1950 -1125);
FORCEPROP 0 LAST CDS_SEC 1
J 0
(1950 -1125);
DISPLAY 1.021277 (1950 -1125);
DISPLAY INVISIBLE (1950 -1125);
FORCEPROP 1 LASTPIN (2100 -1175) $PN 1
J 2
(2088 -1163);
DISPLAY 0.808511 (2088 -1163);
PAINT WHITE (2088 -1163);
DISPLAY INVISIBLE (2088 -1163);
FORCEPROP 1 LASTPIN (1900 -1175) $PN 2
J 2
(1938 -1163);
DISPLAY 0.808511 (1938 -1163);
PAINT WHITE (1938 -1163);
DISPLAY INVISIBLE (1938 -1163);
FORCEADD Q_RES..1
R 2
(2000 -1225);
FORCEPROP 1 LAST VALUE 0
J 0
(2050 -1250);
DISPLAY 0.510638 (2050 -1250);
PAINT SKYBLUE (2050 -1250);
FORCEPROP 1 LAST TOLERANCE 5%
J 2
(2150 -1250);
DISPLAY 0.510638 (2150 -1250);
PAINT SKYBLUE (2150 -1250);
FORCEPROP 1 LAST PACK_TYPE 0402LF
J 2
(2600 -1250);
DISPLAY 0.510638 (2600 -1250);
PAINT SKYBLUE (2600 -1250);
FORCEPROP 1 LAST MATERIAL CHIP
J 2
(2275 -1250);
DISPLAY 0.510638 (2275 -1250);
PAINT SKYBLUE (2275 -1250);
FORCEPROP 1 LAST WATTAGE 1/16W
J 0
(2300 -1250);
DISPLAY 0.510638 (2300 -1250);
PAINT SKYBLUE (2300 -1250);
FORCEPROP 2 LAST CDS_LIB pure_quanta
J 0
(2000 -1225);
DISPLAY INVISIBLE (2000 -1225);
FORCEPROP 1 LAST PATH I127
J 2
(2050 -1075);
DISPLAY 0.978723 (2050 -1075);
PAINT WHITE (2050 -1075);
DISPLAY INVISIBLE (2050 -1075);
FORCEPROP 1 LAST PART_NUMBER CS00002JB13
J 2
(2250 -1200);
DISPLAY 0.510638 (2250 -1200);
PAINT WHITE (2250 -1200);
DISPLAY INVISIBLE (2250 -1200);
FORCEPROP 1 LAST LOCATION R703
J 2
(1875 -1225);
DISPLAY 0.702128 (1875 -1225);
PAINT YELLOW (1875 -1225);
FORCEPROP 0 LAST $SEC 1
J 0
(1950 -1175);
DISPLAY 0.680851 (1950 -1175);
PAINT MONO (1950 -1175);
DISPLAY INVISIBLE (1950 -1175);
FORCEPROP 0 LAST CDS_SEC 1
J 0
(1950 -1175);
DISPLAY 1.021277 (1950 -1175);
DISPLAY INVISIBLE (1950 -1175);
FORCEPROP 1 LASTPIN (2100 -1225) $PN 1
J 2
(2088 -1213);
DISPLAY 0.808511 (2088 -1213);
PAINT WHITE (2088 -1213);
DISPLAY INVISIBLE (2088 -1213);
FORCEPROP 1 LASTPIN (1900 -1225) $PN 2
J 2
(1938 -1213);
DISPLAY 0.808511 (1938 -1213);
PAINT WHITE (1938 -1213);
DISPLAY INVISIBLE (1938 -1213);
FORCEADD Q_RES..1
R 2
(2000 -1300);
FORCEPROP 1 LAST VALUE 0
J 0
(2050 -1325);
DISPLAY 0.510638 (2050 -1325);
PAINT SKYBLUE (2050 -1325);
FORCEPROP 1 LAST TOLERANCE 5%
J 2
(2150 -1325);
DISPLAY 0.510638 (2150 -1325);
PAINT SKYBLUE (2150 -1325);
FORCEPROP 1 LAST MATERIAL EMPTY
J 2
(2275 -1325);
DISPLAY 0.510638 (2275 -1325);
PAINT RED (2275 -1325);
FORCEPROP 1 LAST PACK_TYPE 0402LF
J 2
(2600 -1325);
DISPLAY 0.510638 (2600 -1325);
PAINT SKYBLUE (2600 -1325);
FORCEPROP 1 LAST WATTAGE 1/16W
J 0
(2300 -1325);
DISPLAY 0.510638 (2300 -1325);
PAINT SKYBLUE (2300 -1325);
FORCEPROP 2 LAST CDS_LIB pure_quanta
J 0
(2000 -1300);
DISPLAY INVISIBLE (2000 -1300);
FORCEPROP 1 LAST PATH I128
J 2
(2050 -1150);
DISPLAY 0.978723 (2050 -1150);
PAINT WHITE (2050 -1150);
DISPLAY INVISIBLE (2050 -1150);
FORCEPROP 1 LAST PART_NUMBER CS00002JB13
J 2
(2250 -1275);
DISPLAY 0.510638 (2250 -1275);
PAINT WHITE (2250 -1275);
DISPLAY INVISIBLE (2250 -1275);
FORCEPROP 1 LAST LOCATION R719
J 2
(1875 -1300);
DISPLAY 0.702128 (1875 -1300);
PAINT YELLOW (1875 -1300);
FORCEPROP 0 LAST $SEC 1
J 0
(1950 -1250);
DISPLAY 0.680851 (1950 -1250);
PAINT MONO (1950 -1250);
DISPLAY INVISIBLE (1950 -1250);
FORCEPROP 0 LAST CDS_SEC 1
J 0
(1950 -1250);
DISPLAY 1.021277 (1950 -1250);
DISPLAY INVISIBLE (1950 -1250);
FORCEPROP 1 LASTPIN (2100 -1300) $PN 1
J 2
(2088 -1288);
DISPLAY 0.808511 (2088 -1288);
PAINT WHITE (2088 -1288);
DISPLAY INVISIBLE (2088 -1288);
FORCEPROP 1 LASTPIN (1900 -1300) $PN 2
J 2
(1938 -1288);
DISPLAY 0.808511 (1938 -1288);
PAINT WHITE (1938 -1288);
DISPLAY INVISIBLE (1938 -1288);
FORCEADD OFFPAGE..4
(1000 -625);
FORCEPROP 2 LAST $XR0 47 
J 0
(1186 -625);
DISPLAY 0.638298 (1186 -625);
PAINT MONO (1186 -625);
FORCEPROP 2 LAST CDS_LIB standard
J 0
(1000 -625);
DISPLAY INVISIBLE (1000 -625);
FORCEPROP 1 LAST OFFPAGE TRUE
J 0
(1325 -750);
DISPLAY 0.872340 (1325 -750);
DISPLAY INVISIBLE (1325 -750);
FORCEPROP 1 LAST COMMENT_BODY TRUE
J 0
(975 -725);
DISPLAY 0.872340 (975 -725);
PAINT GREEN (975 -725);
DISPLAY INVISIBLE (975 -725);
FORCEPROP 2 LAST PATH I129
J 0
(1200 -575);
DISPLAY 0.680851 (1200 -575);
DISPLAY INVISIBLE (1200 -575);
FORCEADD OFFPAGE..4
(1000 -725);
FORCEPROP 2 LAST $XR0 47 
J 0
(1186 -725);
DISPLAY 0.638298 (1186 -725);
PAINT MONO (1186 -725);
FORCEPROP 2 LAST CDS_LIB standard
J 0
(1000 -725);
DISPLAY INVISIBLE (1000 -725);
FORCEPROP 1 LAST OFFPAGE TRUE
J 0
(1325 -850);
DISPLAY 0.872340 (1325 -850);
DISPLAY INVISIBLE (1325 -850);
FORCEPROP 1 LAST COMMENT_BODY TRUE
J 0
(975 -825);
DISPLAY 0.872340 (975 -825);
PAINT GREEN (975 -825);
DISPLAY INVISIBLE (975 -825);
FORCEPROP 2 LAST PATH I130
J 0
(1200 -675);
DISPLAY 0.680851 (1200 -675);
DISPLAY INVISIBLE (1200 -675);
FORCEADD OFFPAGE..4
(1000 -675);
FORCEPROP 2 LAST $XR0 47 
J 0
(1186 -675);
DISPLAY 0.638298 (1186 -675);
PAINT MONO (1186 -675);
FORCEPROP 2 LAST CDS_LIB standard
J 0
(1000 -675);
DISPLAY INVISIBLE (1000 -675);
FORCEPROP 1 LAST OFFPAGE TRUE
J 0
(1325 -800);
DISPLAY 0.872340 (1325 -800);
DISPLAY INVISIBLE (1325 -800);
FORCEPROP 1 LAST COMMENT_BODY TRUE
J 0
(975 -775);
DISPLAY 0.872340 (975 -775);
PAINT GREEN (975 -775);
DISPLAY INVISIBLE (975 -775);
FORCEPROP 2 LAST PATH I131
J 0
(1200 -625);
DISPLAY 0.680851 (1200 -625);
DISPLAY INVISIBLE (1200 -625);
FORCEADD OFFPAGE..4
(1000 -825);
FORCEPROP 2 LAST $XR0 47 
J 0
(1186 -825);
DISPLAY 0.638298 (1186 -825);
PAINT MONO (1186 -825);
FORCEPROP 2 LAST CDS_LIB standard
J 0
(1000 -825);
DISPLAY INVISIBLE (1000 -825);
FORCEPROP 1 LAST OFFPAGE TRUE
J 0
(1325 -950);
DISPLAY 0.872340 (1325 -950);
DISPLAY INVISIBLE (1325 -950);
FORCEPROP 1 LAST COMMENT_BODY TRUE
J 0
(975 -925);
DISPLAY 0.872340 (975 -925);
PAINT GREEN (975 -925);
DISPLAY INVISIBLE (975 -925);
FORCEPROP 2 LAST PATH I132
J 0
(1200 -775);
DISPLAY 0.680851 (1200 -775);
DISPLAY INVISIBLE (1200 -775);
FORCEADD OFFPAGE..4
(1000 -775);
FORCEPROP 2 LAST $XR0 47 
J 0
(1186 -775);
DISPLAY 0.638298 (1186 -775);
PAINT MONO (1186 -775);
FORCEPROP 2 LAST CDS_LIB standard
J 0
(1000 -775);
DISPLAY INVISIBLE (1000 -775);
FORCEPROP 1 LAST OFFPAGE TRUE
J 0
(1325 -900);
DISPLAY 0.872340 (1325 -900);
DISPLAY INVISIBLE (1325 -900);
FORCEPROP 1 LAST COMMENT_BODY TRUE
J 0
(975 -875);
DISPLAY 0.872340 (975 -875);
PAINT GREEN (975 -875);
DISPLAY INVISIBLE (975 -875);
FORCEPROP 2 LAST PATH I133
J 0
(1200 -725);
DISPLAY 0.680851 (1200 -725);
DISPLAY INVISIBLE (1200 -725);
FORCEADD OFFPAGE..4
(1000 -875);
FORCEPROP 2 LAST $XR0 47 
J 0
(1186 -875);
DISPLAY 0.638298 (1186 -875);
PAINT MONO (1186 -875);
FORCEPROP 2 LAST CDS_LIB standard
J 0
(1000 -875);
DISPLAY INVISIBLE (1000 -875);
FORCEPROP 1 LAST OFFPAGE TRUE
J 0
(1325 -1000);
DISPLAY 0.872340 (1325 -1000);
DISPLAY INVISIBLE (1325 -1000);
FORCEPROP 1 LAST COMMENT_BODY TRUE
J 0
(975 -975);
DISPLAY 0.872340 (975 -975);
PAINT GREEN (975 -975);
DISPLAY INVISIBLE (975 -975);
FORCEPROP 2 LAST PATH I134
J 0
(1200 -825);
DISPLAY 0.680851 (1200 -825);
DISPLAY INVISIBLE (1200 -825);
FORCEADD OFFPAGE..4
(1000 -975);
FORCEPROP 2 LAST $XR0 47 
J 0
(1186 -975);
DISPLAY 0.638298 (1186 -975);
PAINT MONO (1186 -975);
FORCEPROP 2 LAST CDS_LIB standard
J 0
(1000 -975);
DISPLAY INVISIBLE (1000 -975);
FORCEPROP 1 LAST OFFPAGE TRUE
J 0
(1325 -1100);
DISPLAY 0.872340 (1325 -1100);
DISPLAY INVISIBLE (1325 -1100);
FORCEPROP 1 LAST COMMENT_BODY TRUE
J 0
(975 -1075);
DISPLAY 0.872340 (975 -1075);
PAINT GREEN (975 -1075);
DISPLAY INVISIBLE (975 -1075);
FORCEPROP 2 LAST PATH I135
J 0
(1200 -925);
DISPLAY 0.680851 (1200 -925);
DISPLAY INVISIBLE (1200 -925);
FORCEADD OFFPAGE..4
(1000 -925);
FORCEPROP 2 LAST $XR0 47 
J 0
(1186 -925);
DISPLAY 0.638298 (1186 -925);
PAINT MONO (1186 -925);
FORCEPROP 2 LAST CDS_LIB standard
J 0
(1000 -925);
DISPLAY INVISIBLE (1000 -925);
FORCEPROP 1 LAST OFFPAGE TRUE
J 0
(1325 -1050);
DISPLAY 0.872340 (1325 -1050);
DISPLAY INVISIBLE (1325 -1050);
FORCEPROP 1 LAST COMMENT_BODY TRUE
J 0
(975 -1025);
DISPLAY 0.872340 (975 -1025);
PAINT GREEN (975 -1025);
DISPLAY INVISIBLE (975 -1025);
FORCEPROP 2 LAST PATH I136
J 0
(1200 -875);
DISPLAY 0.680851 (1200 -875);
DISPLAY INVISIBLE (1200 -875);
FORCEADD OFFPAGE..2
(1000 -1075);
FORCEPROP 2 LAST $XR0 50 
J 0
(1189 -1075);
DISPLAY 0.638298 (1189 -1075);
PAINT MONO (1189 -1075);
FORCEPROP 2 LAST CDS_LIB standard
J 0
(1000 -1075);
DISPLAY INVISIBLE (1000 -1075);
FORCEPROP 1 LAST OFFPAGE TRUE
J 0
(1325 -1200);
DISPLAY 0.872340 (1325 -1200);
DISPLAY INVISIBLE (1325 -1200);
FORCEPROP 1 LAST COMMENT_BODY TRUE
J 0
(955 -1170);
DISPLAY 0.872340 (955 -1170);
PAINT GREEN (955 -1170);
DISPLAY INVISIBLE (955 -1170);
FORCEPROP 2 LAST PATH I137
J 0
(1200 -1025);
DISPLAY 0.680851 (1200 -1025);
DISPLAY INVISIBLE (1200 -1025);
FORCEADD OFFPAGE..2
(1000 -1025);
FORCEPROP 2 LAST $XR0 50 
J 0
(1189 -1025);
DISPLAY 0.638298 (1189 -1025);
PAINT MONO (1189 -1025);
FORCEPROP 2 LAST CDS_LIB standard
J 0
(1000 -1025);
DISPLAY INVISIBLE (1000 -1025);
FORCEPROP 1 LAST OFFPAGE TRUE
J 0
(1325 -1150);
DISPLAY 0.872340 (1325 -1150);
DISPLAY INVISIBLE (1325 -1150);
FORCEPROP 1 LAST COMMENT_BODY TRUE
J 0
(955 -1120);
DISPLAY 0.872340 (955 -1120);
PAINT GREEN (955 -1120);
DISPLAY INVISIBLE (955 -1120);
FORCEPROP 2 LAST PATH I138
J 0
(1200 -975);
DISPLAY 0.680851 (1200 -975);
DISPLAY INVISIBLE (1200 -975);
FORCEADD OFFPAGE..2
(1000 -1375);
FORCEPROP 2 LAST $XR0 28 
J 0
(1189 -1375);
DISPLAY 0.638298 (1189 -1375);
PAINT MONO (1189 -1375);
FORCEPROP 2 LAST CDS_LIB standard
J 0
(1000 -1375);
DISPLAY INVISIBLE (1000 -1375);
FORCEPROP 1 LAST OFFPAGE TRUE
J 0
(1325 -1500);
DISPLAY 0.872340 (1325 -1500);
DISPLAY INVISIBLE (1325 -1500);
FORCEPROP 1 LAST COMMENT_BODY TRUE
J 0
(955 -1470);
DISPLAY 0.872340 (955 -1470);
PAINT GREEN (955 -1470);
DISPLAY INVISIBLE (955 -1470);
FORCEPROP 2 LAST PATH I139
J 0
(1200 -1325);
DISPLAY 0.680851 (1200 -1325);
DISPLAY INVISIBLE (1200 -1325);
FORCEADD UNIVERSAL_GND..1
R 5
(-1150 -675);
FORCEPROP 3 LASTPIN (-1100 -675) SIG_NAME GND\g
J 0
(-1090 -665);
DISPLAY 0.659574 (-1090 -665);
PAINT MONO (-1090 -665);
DISPLAY INVISIBLE (-1090 -665);
FORCEPROP 2 LAST CDS_LIB logical_power
R 3
J 0
(-1150 -675);
DISPLAY INVISIBLE (-1150 -675);
FORCEPROP 1 LAST HDL_POWER GND
R 3
J 1
(-1225 -700);
DISPLAY 0.702128 (-1225 -700);
PAINT GREEN (-1225 -700);
DISPLAY INVISIBLE (-1225 -700);
FORCEPROP 1 LAST PATH I140
R 3
J 0
(-1150 -750);
DISPLAY 0.872340 (-1150 -750);
PAINT AQUA (-1150 -750);
DISPLAY INVISIBLE (-1150 -750);
FORCEADD PCA9555PW..1
(-425 -975);
FORCEPROP 1 LAST PART_NUMBER TMP_QAL009555K04
J 0
(-650 -415);
DISPLAY 0.723404 (-650 -415);
PAINT GREEN (-650 -415);
FORCEPROP 2 LAST PACK_TYPE SMLF
J 0
(-650 -325);
DISPLAY 0.680851 (-650 -325);
FORCEPROP 1 LAST MATERIAL IC
J 0
(-650 -465);
DISPLAY 0.723404 (-650 -465);
PAINT GREEN (-650 -465);
FORCEPROP 2 LAST VALUE PCA9555PW
J 0
(-650 -275);
DISPLAY 0.680851 (-650 -275);
FORCEPROP 2 LAST SEC_TYPE SMLF
J 0
(-650 -225);
DISPLAY 0.680851 (-650 -225);
DISPLAY INVISIBLE (-650 -225);
FORCEPROP 1 LAST NEEDS_NO_SIZE TRUE
J 0
(-425 -975);
DISPLAY 0.468085 (-425 -975);
PAINT GREEN (-425 -975);
DISPLAY INVISIBLE (-425 -975);
FORCEPROP 2 LAST CDS_LIB pure_quanta
J 0
(-425 -975);
DISPLAY INVISIBLE (-425 -975);
FORCEPROP 1 LAST PATH I141
J 0
(-225 -470);
DISPLAY 0.723404 (-225 -470);
PAINT GREEN (-225 -470);
DISPLAY INVISIBLE (-225 -470);
FORCEPROP 1 LAST LOCATION U40
J 0
(-650 -370);
DISPLAY 0.723404 (-650 -370);
PAINT GREEN (-650 -370);
FORCEPROP 0 LASTPIN (-800 -875) $PN 21
J 2
(-810 -865);
DISPLAY 0.680851 (-810 -865);
PAINT MONO (-810 -865);
FORCEPROP 0 LASTPIN (-800 -925) $PN 2
J 2
(-810 -915);
DISPLAY 0.680851 (-810 -915);
PAINT MONO (-810 -915);
FORCEPROP 0 LASTPIN (-800 -975) $PN 3
J 2
(-810 -965);
DISPLAY 0.680851 (-810 -965);
PAINT MONO (-810 -965);
FORCEPROP 0 LASTPIN (-800 -775) $PN 1
J 2
(-810 -765);
DISPLAY 0.680851 (-810 -765);
PAINT MONO (-810 -765);
FORCEPROP 0 LASTPIN (-50 -625) $PN 4
J 0
(-40 -615);
DISPLAY 0.680851 (-40 -615);
PAINT MONO (-40 -615);
FORCEPROP 0 LASTPIN (-50 -675) $PN 5
J 0
(-40 -665);
DISPLAY 0.680851 (-40 -665);
PAINT MONO (-40 -665);
FORCEPROP 0 LASTPIN (-50 -725) $PN 6
J 0
(-40 -715);
DISPLAY 0.680851 (-40 -715);
PAINT MONO (-40 -715);
FORCEPROP 0 LASTPIN (-50 -775) $PN 7
J 0
(-40 -765);
DISPLAY 0.680851 (-40 -765);
PAINT MONO (-40 -765);
FORCEPROP 0 LASTPIN (-50 -825) $PN 8
J 0
(-40 -815);
DISPLAY 0.680851 (-40 -815);
PAINT MONO (-40 -815);
FORCEPROP 0 LASTPIN (-50 -875) $PN 9
J 0
(-40 -865);
DISPLAY 0.680851 (-40 -865);
PAINT MONO (-40 -865);
FORCEPROP 0 LASTPIN (-50 -925) $PN 10
J 0
(-40 -915);
DISPLAY 0.680851 (-40 -915);
PAINT MONO (-40 -915);
FORCEPROP 0 LASTPIN (-50 -975) $PN 11
J 0
(-40 -965);
DISPLAY 0.680851 (-40 -965);
PAINT MONO (-40 -965);
FORCEPROP 0 LASTPIN (-50 -1025) $PN 13
J 0
(-40 -1015);
DISPLAY 0.680851 (-40 -1015);
PAINT MONO (-40 -1015);
FORCEPROP 0 LASTPIN (-50 -1075) $PN 14
J 0
(-40 -1065);
DISPLAY 0.680851 (-40 -1065);
PAINT MONO (-40 -1065);
FORCEPROP 0 LASTPIN (-50 -1125) $PN 15
J 0
(-40 -1115);
DISPLAY 0.680851 (-40 -1115);
PAINT MONO (-40 -1115);
FORCEPROP 0 LASTPIN (-50 -1175) $PN 16
J 0
(-40 -1165);
DISPLAY 0.680851 (-40 -1165);
PAINT MONO (-40 -1165);
FORCEPROP 0 LASTPIN (-50 -1225) $PN 17
J 0
(-40 -1215);
DISPLAY 0.680851 (-40 -1215);
PAINT MONO (-40 -1215);
FORCEPROP 0 LASTPIN (-50 -1275) $PN 18
J 0
(-40 -1265);
DISPLAY 0.680851 (-40 -1265);
PAINT MONO (-40 -1265);
FORCEPROP 0 LASTPIN (-50 -1325) $PN 19
J 0
(-40 -1315);
DISPLAY 0.680851 (-40 -1315);
PAINT MONO (-40 -1315);
FORCEPROP 0 LASTPIN (-50 -1375) $PN 20
J 0
(-40 -1365);
DISPLAY 0.680851 (-40 -1365);
PAINT MONO (-40 -1365);
FORCEPROP 0 LASTPIN (-800 -1325) $PN 22
J 2
(-810 -1315);
DISPLAY 0.680851 (-810 -1315);
PAINT MONO (-810 -1315);
FORCEPROP 0 LASTPIN (-800 -1225) $PN 23
J 2
(-810 -1215);
DISPLAY 0.680851 (-810 -1215);
PAINT MONO (-810 -1215);
FORCEPROP 0 LASTPIN (-800 -575) $PN 24
J 2
(-810 -565);
DISPLAY 0.680851 (-810 -565);
PAINT MONO (-810 -565);
FORCEPROP 0 LASTPIN (-800 -675) $PN 12
J 2
(-810 -665);
DISPLAY 0.680851 (-810 -665);
PAINT MONO (-810 -665);
FORCEPROP 2 LAST SEC 1
J 0
(-650 -225);
DISPLAY 0.680851 (-650 -225);
PAINT MONO (-650 -225);
DISPLAY INVISIBLE (-650 -225);
FORCEADD OFFPAGE..4
(3625 -1625);
FORCEPROP 2 LAST $XR2 13 
J 0
(3991 -1625);
DISPLAY 0.638298 (3991 -1625);
PAINT MONO (3991 -1625);
FORCEPROP 2 LAST $XR1 34 
J 0
(3901 -1625);
DISPLAY 0.638298 (3901 -1625);
PAINT MONO (3901 -1625);
FORCEPROP 2 LAST $XR0 11 
J 0
(3811 -1625);
DISPLAY 0.638298 (3811 -1625);
PAINT MONO (3811 -1625);
FORCEPROP 2 LAST CDS_LIB standard
J 0
(3625 -1625);
DISPLAY INVISIBLE (3625 -1625);
FORCEPROP 1 LAST OFFPAGE TRUE
J 0
(3950 -1750);
DISPLAY 0.872340 (3950 -1750);
DISPLAY INVISIBLE (3950 -1750);
FORCEPROP 1 LAST COMMENT_BODY TRUE
J 0
(3600 -1725);
DISPLAY 0.872340 (3600 -1725);
PAINT GREEN (3600 -1725);
DISPLAY INVISIBLE (3600 -1725);
FORCEPROP 2 LAST PATH I142
J 0
(4000 -1575);
DISPLAY 0.680851 (4000 -1575);
DISPLAY INVISIBLE (4000 -1575);
FORCEADD OFFPAGE..4
(3625 -1825);
FORCEPROP 2 LAST $XR1 35 
J 0
(3901 -1825);
DISPLAY 0.638298 (3901 -1825);
PAINT MONO (3901 -1825);
FORCEPROP 2 LAST $XR0 13 
J 0
(3811 -1825);
DISPLAY 0.638298 (3811 -1825);
PAINT MONO (3811 -1825);
FORCEPROP 2 LAST CDS_LIB standard
J 0
(3625 -1825);
DISPLAY INVISIBLE (3625 -1825);
FORCEPROP 1 LAST OFFPAGE TRUE
J 0
(3950 -1950);
DISPLAY 0.872340 (3950 -1950);
DISPLAY INVISIBLE (3950 -1950);
FORCEPROP 1 LAST COMMENT_BODY TRUE
J 0
(3600 -1925);
DISPLAY 0.872340 (3600 -1925);
PAINT GREEN (3600 -1925);
DISPLAY INVISIBLE (3600 -1925);
FORCEPROP 2 LAST PATH I143
J 0
(3925 -1775);
DISPLAY 0.680851 (3925 -1775);
DISPLAY INVISIBLE (3925 -1775);
FORCEADD Q_RES..1
R 2
(2000 -1625);
FORCEPROP 1 LAST VALUE 0
J 0
(2050 -1650);
DISPLAY 0.510638 (2050 -1650);
PAINT SKYBLUE (2050 -1650);
FORCEPROP 1 LAST TOLERANCE 5%
J 2
(2150 -1650);
DISPLAY 0.510638 (2150 -1650);
PAINT SKYBLUE (2150 -1650);
FORCEPROP 1 LAST PACK_TYPE 0402LF
J 2
(2600 -1650);
DISPLAY 0.510638 (2600 -1650);
PAINT SKYBLUE (2600 -1650);
FORCEPROP 1 LAST WATTAGE 1/16W
J 0
(2300 -1650);
DISPLAY 0.510638 (2300 -1650);
PAINT SKYBLUE (2300 -1650);
FORCEPROP 1 LAST MATERIAL CHIP
J 2
(2275 -1650);
DISPLAY 0.510638 (2275 -1650);
PAINT SKYBLUE (2275 -1650);
FORCEPROP 2 LAST CDS_LIB pure_quanta
J 0
(2000 -1625);
DISPLAY INVISIBLE (2000 -1625);
FORCEPROP 1 LAST PATH I144
J 2
(2050 -1475);
DISPLAY 0.978723 (2050 -1475);
PAINT WHITE (2050 -1475);
DISPLAY INVISIBLE (2050 -1475);
FORCEPROP 1 LAST PART_NUMBER CS00002JB13
J 2
(2250 -1600);
DISPLAY 0.510638 (2250 -1600);
PAINT WHITE (2250 -1600);
DISPLAY INVISIBLE (2250 -1600);
FORCEPROP 1 LAST LOCATION R720
J 2
(1875 -1625);
DISPLAY 0.702128 (1875 -1625);
PAINT YELLOW (1875 -1625);
FORCEPROP 0 LAST $SEC 1
J 0
(1950 -1575);
DISPLAY 0.680851 (1950 -1575);
PAINT MONO (1950 -1575);
DISPLAY INVISIBLE (1950 -1575);
FORCEPROP 0 LAST CDS_SEC 1
J 0
(1950 -1575);
DISPLAY 1.021277 (1950 -1575);
DISPLAY INVISIBLE (1950 -1575);
FORCEPROP 1 LASTPIN (2100 -1625) $PN 1
J 2
(2088 -1613);
DISPLAY 0.808511 (2088 -1613);
PAINT WHITE (2088 -1613);
DISPLAY INVISIBLE (2088 -1613);
FORCEPROP 1 LASTPIN (1900 -1625) $PN 2
J 2
(1938 -1613);
DISPLAY 0.808511 (1938 -1613);
PAINT WHITE (1938 -1613);
DISPLAY INVISIBLE (1938 -1613);
FORCEADD Q_RES..1
R 2
(2025 -1825);
FORCEPROP 1 LAST VALUE 0
J 0
(2075 -1850);
DISPLAY 0.510638 (2075 -1850);
PAINT SKYBLUE (2075 -1850);
FORCEPROP 1 LAST TOLERANCE 5%
J 2
(2175 -1850);
DISPLAY 0.510638 (2175 -1850);
PAINT SKYBLUE (2175 -1850);
FORCEPROP 1 LAST WATTAGE 1/16W
J 0
(2325 -1850);
DISPLAY 0.510638 (2325 -1850);
PAINT SKYBLUE (2325 -1850);
FORCEPROP 1 LAST PACK_TYPE 0402LF
J 2
(2625 -1850);
DISPLAY 0.510638 (2625 -1850);
PAINT SKYBLUE (2625 -1850);
FORCEPROP 1 LAST MATERIAL CHIP
J 2
(2300 -1850);
DISPLAY 0.510638 (2300 -1850);
PAINT SKYBLUE (2300 -1850);
FORCEPROP 2 LAST CDS_LIB pure_quanta
J 0
(2025 -1825);
DISPLAY INVISIBLE (2025 -1825);
FORCEPROP 1 LAST PATH I145
J 2
(2075 -1675);
DISPLAY 0.978723 (2075 -1675);
PAINT WHITE (2075 -1675);
DISPLAY INVISIBLE (2075 -1675);
FORCEPROP 1 LAST PART_NUMBER CS00002JB13
J 2
(2275 -1800);
DISPLAY 0.510638 (2275 -1800);
PAINT WHITE (2275 -1800);
DISPLAY INVISIBLE (2275 -1800);
FORCEPROP 1 LAST LOCATION R721
J 2
(1900 -1825);
DISPLAY 0.702128 (1900 -1825);
PAINT YELLOW (1900 -1825);
FORCEPROP 0 LAST $SEC 1
J 0
(1975 -1775);
DISPLAY 0.680851 (1975 -1775);
PAINT MONO (1975 -1775);
DISPLAY INVISIBLE (1975 -1775);
FORCEPROP 0 LAST CDS_SEC 1
J 0
(1975 -1775);
DISPLAY 1.021277 (1975 -1775);
DISPLAY INVISIBLE (1975 -1775);
FORCEPROP 1 LASTPIN (2125 -1825) $PN 1
J 2
(2113 -1813);
DISPLAY 0.808511 (2113 -1813);
PAINT WHITE (2113 -1813);
DISPLAY INVISIBLE (2113 -1813);
FORCEPROP 1 LASTPIN (1925 -1825) $PN 2
J 2
(1963 -1813);
DISPLAY 0.808511 (1963 -1813);
PAINT WHITE (1963 -1813);
DISPLAY INVISIBLE (1963 -1813);
FORCEADD Q_CAP..1
(-1475 -300);
FORCEPROP 1 LAST VALUE 0.1UF
J 0
(-1425 -250);
DISPLAY 0.510638 (-1425 -250);
PAINT SKYBLUE (-1425 -250);
FORCEPROP 1 LAST PACK_TYPE 0402
J 0
(-1425 -500);
DISPLAY 0.510638 (-1425 -500);
PAINT SKYBLUE (-1425 -500);
FORCEPROP 1 LAST PART_NUMBER CH4104K1B00
J 0
(-1425 -450);
DISPLAY 0.510638 (-1425 -450);
PAINT WHITE (-1425 -450);
FORCEPROP 1 LAST MATERIAL X7R
J 0
(-1425 -400);
DISPLAY 0.510638 (-1425 -400);
PAINT SKYBLUE (-1425 -400);
FORCEPROP 1 LAST TOLERANCE 10%
J 0
(-1425 -350);
DISPLAY 0.510638 (-1425 -350);
PAINT SKYBLUE (-1425 -350);
FORCEPROP 1 LAST VOLTAGE 25V
J 0
(-1425 -300);
DISPLAY 0.510638 (-1425 -300);
PAINT SKYBLUE (-1425 -300);
FORCEPROP 2 LAST CDS_LIB pure_quanta
J 0
(-1475 -300);
DISPLAY INVISIBLE (-1475 -300);
FORCEPROP 1 LAST PATH I146
J 0
(-1425 -150);
DISPLAY 0.978723 (-1425 -150);
PAINT WHITE (-1425 -150);
DISPLAY INVISIBLE (-1425 -150);
FORCEPROP 1 LAST LOCATION C300
J 0
(-1425 -200);
DISPLAY 0.702128 (-1425 -200);
PAINT YELLOW (-1425 -200);
FORCEPROP 0 LAST $SEC 1
J 0
(-1425 -150);
DISPLAY 0.680851 (-1425 -150);
PAINT MONO (-1425 -150);
DISPLAY INVISIBLE (-1425 -150);
FORCEPROP 0 LAST CDS_SEC 1
J 0
(-1425 -150);
DISPLAY 1.021277 (-1425 -150);
DISPLAY INVISIBLE (-1425 -150);
FORCEPROP 1 LASTPIN (-1475 -200) $PN 1
J 0
(-1465 -220);
DISPLAY 0.808511 (-1465 -220);
PAINT WHITE (-1465 -220);
DISPLAY INVISIBLE (-1465 -220);
FORCEPROP 1 LASTPIN (-1475 -400) $PN 2
J 0
(-1465 -420);
DISPLAY 0.808511 (-1465 -420);
PAINT WHITE (-1465 -420);
DISPLAY INVISIBLE (-1465 -420);
FORCEADD Q_RES..2
R 2
(-1775 -325);
FORCEPROP 1 LAST TOLERANCE 1%
J 2
(-1820 -300);
DISPLAY 0.978723 (-1820 -300);
FORCEPROP 1 LAST MATERIAL CHIP
J 2
(-1815 -400);
DISPLAY 0.978723 (-1815 -400);
FORCEPROP 1 LAST PACK_TYPE 0402LF
J 2
(-1815 -500);
DISPLAY 0.978723 (-1815 -500);
FORCEPROP 1 LAST VALUE 4.7K
J 2
(-1820 -250);
DISPLAY 0.978723 (-1820 -250);
FORCEPROP 1 LAST PART_NUMBER CS24702FB06
J 2
(-1815 -450);
DISPLAY 0.978723 (-1815 -450);
FORCEPROP 1 LAST WATTAGE 1/16W
J 2
(-1815 -350);
DISPLAY 0.978723 (-1815 -350);
FORCEPROP 2 LAST CDS_LIB pure_quanta
J 2
(-1775 -325);
DISPLAY INVISIBLE (-1775 -325);
FORCEPROP 1 LAST PATH I147
J 2
(-1825 -150);
DISPLAY 0.978723 (-1825 -150);
PAINT WHITE (-1825 -150);
DISPLAY INVISIBLE (-1825 -150);
FORCEPROP 1 LAST LOCATION R667
J 2
(-1820 -200);
DISPLAY 0.978723 (-1820 -200);
FORCEPROP 1 LASTPIN (-1775 -225) $PN 1
J 2
(-1780 -263);
DISPLAY 0.787234 (-1780 -263);
PAINT MONO (-1780 -263);
FORCEPROP 1 LASTPIN (-1775 -425) $PN 2
J 2
(-1780 -415);
DISPLAY 0.787234 (-1780 -415);
PAINT MONO (-1780 -415);
FORCEPROP 0 LAST $SEC 1
J 2
(-1825 -150);
DISPLAY 0.680851 (-1825 -150);
PAINT MONO (-1825 -150);
DISPLAY INVISIBLE (-1825 -150);
FORCEPROP 0 LAST CDS_SEC 1
J 2
(-1825 -150);
DISPLAY 0.680851 (-1825 -150);
DISPLAY INVISIBLE (-1825 -150);
FORCEADD UNIVERSAL_GND..1
(-1475 -550);
FORCEPROP 3 LASTPIN (-1475 -500) SIG_NAME GND\g
J 0
(-1465 -490);
DISPLAY 0.659574 (-1465 -490);
PAINT MONO (-1465 -490);
DISPLAY INVISIBLE (-1465 -490);
FORCEPROP 2 LAST CDS_LIB logical_power
J 0
(-1475 -550);
DISPLAY INVISIBLE (-1475 -550);
FORCEPROP 1 LAST HDL_POWER GND
J 1
(-1450 -625);
DISPLAY 0.702128 (-1450 -625);
PAINT GREEN (-1450 -625);
DISPLAY INVISIBLE (-1450 -625);
FORCEPROP 1 LAST PATH I148
J 0
(-1400 -550);
DISPLAY 0.872340 (-1400 -550);
PAINT AQUA (-1400 -550);
DISPLAY INVISIBLE (-1400 -550);
FORCEADD OFFPAGE..1
(-1575 -875);
FORCEPROP 2 LAST $XR0 28 
J 0
(-1796 -875);
DISPLAY 0.638298 (-1796 -875);
PAINT MONO (-1796 -875);
FORCEPROP 2 LAST CDS_LIB standard
J 0
(-1575 -875);
DISPLAY INVISIBLE (-1575 -875);
FORCEPROP 1 LAST OFFPAGE TRUE
J 0
(-1250 -1000);
DISPLAY 0.872340 (-1250 -1000);
PAINT GREEN (-1250 -1000);
DISPLAY INVISIBLE (-1250 -1000);
FORCEPROP 1 LAST COMMENT_BODY TRUE
J 0
(-1450 -975);
DISPLAY 0.872340 (-1450 -975);
PAINT PEACH (-1450 -975);
DISPLAY INVISIBLE (-1450 -975);
FORCEPROP 2 LAST PATH I149
J 0
(-1525 -800);
DISPLAY 0.680851 (-1525 -800);
DISPLAY INVISIBLE (-1525 -800);
FORCEADD OFFPAGE..1
(-1575 -925);
FORCEPROP 2 LAST $XR0 28 
J 0
(-1796 -925);
DISPLAY 0.638298 (-1796 -925);
PAINT MONO (-1796 -925);
FORCEPROP 2 LAST CDS_LIB standard
J 0
(-1575 -925);
DISPLAY INVISIBLE (-1575 -925);
FORCEPROP 1 LAST OFFPAGE TRUE
J 0
(-1250 -1050);
DISPLAY 0.872340 (-1250 -1050);
PAINT GREEN (-1250 -1050);
DISPLAY INVISIBLE (-1250 -1050);
FORCEPROP 1 LAST COMMENT_BODY TRUE
J 0
(-1450 -1025);
DISPLAY 0.872340 (-1450 -1025);
PAINT PEACH (-1450 -1025);
DISPLAY INVISIBLE (-1450 -1025);
FORCEPROP 2 LAST PATH I150
J 0
(-1525 -850);
DISPLAY 0.680851 (-1525 -850);
DISPLAY INVISIBLE (-1525 -850);
FORCEADD OFFPAGE..1
(-1575 -975);
FORCEPROP 2 LAST $XR0 28 
J 0
(-1796 -975);
DISPLAY 0.638298 (-1796 -975);
PAINT MONO (-1796 -975);
FORCEPROP 2 LAST CDS_LIB standard
J 0
(-1575 -975);
DISPLAY INVISIBLE (-1575 -975);
FORCEPROP 1 LAST OFFPAGE TRUE
J 0
(-1250 -1100);
DISPLAY 0.872340 (-1250 -1100);
PAINT GREEN (-1250 -1100);
DISPLAY INVISIBLE (-1250 -1100);
FORCEPROP 1 LAST COMMENT_BODY TRUE
J 0
(-1450 -1075);
DISPLAY 0.872340 (-1450 -1075);
PAINT PEACH (-1450 -1075);
DISPLAY INVISIBLE (-1450 -1075);
FORCEPROP 2 LAST PATH I151
J 0
(-1525 -900);
DISPLAY 0.680851 (-1525 -900);
DISPLAY INVISIBLE (-1525 -900);
FORCEADD Q_RES..1
(-2400 -1225);
FORCEPROP 1 LAST TOLERANCE 5%
J 0
(-2550 -1250);
DISPLAY 0.510638 (-2550 -1250);
PAINT SKYBLUE (-2550 -1250);
FORCEPROP 1 LAST MATERIAL CHIP
J 0
(-2675 -1250);
DISPLAY 0.510638 (-2675 -1250);
PAINT SKYBLUE (-2675 -1250);
FORCEPROP 1 LAST VALUE 0
J 2
(-2450 -1250);
DISPLAY 0.510638 (-2450 -1250);
PAINT SKYBLUE (-2450 -1250);
FORCEPROP 1 LAST WATTAGE 1/16W
J 2
(-2700 -1250);
DISPLAY 0.510638 (-2700 -1250);
PAINT SKYBLUE (-2700 -1250);
FORCEPROP 1 LAST PACK_TYPE 0402LF
J 0
(-3000 -1250);
DISPLAY 0.510638 (-3000 -1250);
PAINT SKYBLUE (-3000 -1250);
FORCEPROP 2 LAST CDS_LIB pure_quanta
J 2
(-2400 -1225);
DISPLAY INVISIBLE (-2400 -1225);
FORCEPROP 1 LAST PATH I152
J 0
(-2450 -1075);
DISPLAY 0.978723 (-2450 -1075);
PAINT WHITE (-2450 -1075);
DISPLAY INVISIBLE (-2450 -1075);
FORCEPROP 1 LAST PART_NUMBER CS00002JB13
J 0
(-2650 -1200);
DISPLAY 0.510638 (-2650 -1200);
PAINT WHITE (-2650 -1200);
DISPLAY INVISIBLE (-2650 -1200);
FORCEPROP 1 LAST LOCATION R95
J 0
(-2350 -1225);
DISPLAY 0.702128 (-2350 -1225);
PAINT YELLOW (-2350 -1225);
FORCEPROP 0 LAST $SEC 1
J 2
(-2350 -1175);
DISPLAY 0.680851 (-2350 -1175);
PAINT MONO (-2350 -1175);
DISPLAY INVISIBLE (-2350 -1175);
FORCEPROP 0 LAST CDS_SEC 1
J 2
(-2350 -1175);
DISPLAY 1.021277 (-2350 -1175);
DISPLAY INVISIBLE (-2350 -1175);
FORCEPROP 1 LASTPIN (-2500 -1225) $PN 1
J 0
(-2488 -1213);
DISPLAY 0.808511 (-2488 -1213);
PAINT WHITE (-2488 -1213);
DISPLAY INVISIBLE (-2488 -1213);
FORCEPROP 1 LASTPIN (-2300 -1225) $PN 2
J 0
(-2338 -1213);
DISPLAY 0.808511 (-2338 -1213);
PAINT WHITE (-2338 -1213);
DISPLAY INVISIBLE (-2338 -1213);
FORCEADD Q_RES..1
(-2400 -1325);
FORCEPROP 1 LAST VALUE 0
J 2
(-2450 -1350);
DISPLAY 0.510638 (-2450 -1350);
PAINT SKYBLUE (-2450 -1350);
FORCEPROP 1 LAST WATTAGE 1/16W
J 2
(-2700 -1350);
DISPLAY 0.510638 (-2700 -1350);
PAINT SKYBLUE (-2700 -1350);
FORCEPROP 1 LAST MATERIAL CHIP
J 0
(-2675 -1350);
DISPLAY 0.510638 (-2675 -1350);
PAINT SKYBLUE (-2675 -1350);
FORCEPROP 1 LAST PACK_TYPE 0402LF
J 0
(-3000 -1350);
DISPLAY 0.510638 (-3000 -1350);
PAINT SKYBLUE (-3000 -1350);
FORCEPROP 1 LAST TOLERANCE 5%
J 0
(-2550 -1350);
DISPLAY 0.510638 (-2550 -1350);
PAINT SKYBLUE (-2550 -1350);
FORCEPROP 2 LAST CDS_LIB pure_quanta
J 2
(-2400 -1325);
DISPLAY INVISIBLE (-2400 -1325);
FORCEPROP 1 LAST PATH I153
J 0
(-2450 -1175);
DISPLAY 0.978723 (-2450 -1175);
PAINT WHITE (-2450 -1175);
DISPLAY INVISIBLE (-2450 -1175);
FORCEPROP 1 LAST PART_NUMBER CS00002JB13
J 0
(-2650 -1300);
DISPLAY 0.510638 (-2650 -1300);
PAINT WHITE (-2650 -1300);
DISPLAY INVISIBLE (-2650 -1300);
FORCEPROP 1 LAST LOCATION R632
J 0
(-2350 -1325);
DISPLAY 0.702128 (-2350 -1325);
PAINT YELLOW (-2350 -1325);
FORCEPROP 0 LAST $SEC 1
J 2
(-2350 -1275);
DISPLAY 0.680851 (-2350 -1275);
PAINT MONO (-2350 -1275);
DISPLAY INVISIBLE (-2350 -1275);
FORCEPROP 0 LAST CDS_SEC 1
J 2
(-2350 -1275);
DISPLAY 1.021277 (-2350 -1275);
DISPLAY INVISIBLE (-2350 -1275);
FORCEPROP 1 LASTPIN (-2500 -1325) $PN 1
J 0
(-2488 -1313);
DISPLAY 0.808511 (-2488 -1313);
PAINT WHITE (-2488 -1313);
DISPLAY INVISIBLE (-2488 -1313);
FORCEPROP 1 LASTPIN (-2300 -1325) $PN 2
J 0
(-2338 -1313);
DISPLAY 0.808511 (-2338 -1313);
PAINT WHITE (-2338 -1313);
DISPLAY INVISIBLE (-2338 -1313);
FORCEADD UNIVERSAL_POWER..1
(-1150 -25);
FORCEPROP 3 LASTPIN (-1150 -75) SIG_NAME P3V3_AUX\g
J 0
(-1140 -65);
DISPLAY 0.659574 (-1140 -65);
PAINT MONO (-1140 -65);
DISPLAY INVISIBLE (-1140 -65);
FORCEPROP 1 LAST HDL_POWER P3V3_AUX
J 1
(-1150 25);
DISPLAY 0.702128 (-1150 25);
PAINT PEACH (-1150 25);
FORCEPROP 2 LAST CDS_LIB logical_power
J 0
(-1150 -25);
DISPLAY INVISIBLE (-1150 -25);
FORCEPROP 1 LAST PATH I154
J 0
(-1100 0);
DISPLAY 0.872340 (-1100 0);
PAINT AQUA (-1100 0);
DISPLAY INVISIBLE (-1100 0);
FORCEADD UNIVERSAL_POWER..1
(-1775 0);
FORCEPROP 3 LASTPIN (-1775 -50) SIG_NAME P3V3_AUX\g
J 0
(-1765 -40);
DISPLAY 0.659574 (-1765 -40);
PAINT MONO (-1765 -40);
DISPLAY INVISIBLE (-1765 -40);
FORCEPROP 1 LAST HDL_POWER P3V3_AUX
J 1
(-1775 50);
DISPLAY 0.702128 (-1775 50);
PAINT PEACH (-1775 50);
FORCEPROP 2 LAST CDS_LIB logical_power
J 0
(-1775 0);
DISPLAY INVISIBLE (-1775 0);
FORCEPROP 1 LAST PATH I155
J 0
(-1725 25);
DISPLAY 0.872340 (-1725 25);
PAINT AQUA (-1725 25);
DISPLAY INVISIBLE (-1725 25);
FORCEADD OFFPAGE..1
(-3675 -1325);
FORCEPROP 2 LAST $XR1 29 
J 0
(-4016 -1325);
DISPLAY 0.638298 (-4016 -1325);
PAINT MONO (-4016 -1325);
FORCEPROP 2 LAST $XR0 28 
J 0
(-3926 -1325);
DISPLAY 0.638298 (-3926 -1325);
PAINT MONO (-3926 -1325);
FORCEPROP 2 LAST CDS_LIB standard
J 0
(-3675 -1325);
PAINT MONO (-3675 -1325);
DISPLAY INVISIBLE (-3675 -1325);
FORCEPROP 1 LAST OFFPAGE TRUE
J 0
(-3350 -1450);
DISPLAY 0.872340 (-3350 -1450);
DISPLAY INVISIBLE (-3350 -1450);
FORCEPROP 1 LAST COMMENT_BODY TRUE
J 0
(-3550 -1425);
DISPLAY 0.872340 (-3550 -1425);
PAINT GREEN (-3550 -1425);
DISPLAY INVISIBLE (-3550 -1425);
FORCEPROP 2 LAST PATH I156
J 0
(-3875 -1275);
DISPLAY 0.680851 (-3875 -1275);
DISPLAY INVISIBLE (-3875 -1275);
FORCEADD OFFPAGE..6
(-3675 -1225);
FORCEPROP 2 LAST $XR1 29 
J 0
(-4044 -1225);
DISPLAY 0.638298 (-4044 -1225);
PAINT MONO (-4044 -1225);
FORCEPROP 2 LAST $XR0 28 
J 0
(-3954 -1225);
DISPLAY 0.638298 (-3954 -1225);
PAINT MONO (-3954 -1225);
FORCEPROP 2 LAST CDS_LIB standard
J 0
(-3675 -1225);
PAINT MONO (-3675 -1225);
DISPLAY INVISIBLE (-3675 -1225);
FORCEPROP 1 LAST OFFPAGE TRUE
J 0
(-3350 -1350);
DISPLAY 0.872340 (-3350 -1350);
DISPLAY INVISIBLE (-3350 -1350);
FORCEPROP 1 LAST COMMENT_BODY TRUE
J 0
(-3575 -1300);
DISPLAY 0.872340 (-3575 -1300);
PAINT GREEN (-3575 -1300);
DISPLAY INVISIBLE (-3575 -1300);
FORCEPROP 2 LAST PATH I157
J 0
(-3900 -1175);
DISPLAY 0.680851 (-3900 -1175);
DISPLAY INVISIBLE (-3900 -1175);
FORCEADD OFFPAGE..2
(4775 300);
FORCEPROP 2 LAST $XR0 10 
J 0
(4964 300);
DISPLAY 0.638298 (4964 300);
PAINT MONO (4964 300);
FORCEPROP 2 LAST $XR1 15 
J 0
(5054 300);
DISPLAY 0.638298 (5054 300);
PAINT MONO (5054 300);
FORCEPROP 2 LAST $XR2 36 
J 0
(4964 264);
DISPLAY 0.638298 (4964 264);
PAINT MONO (4964 264);
FORCEPROP 2 LAST PATH I158
J 0
(5075 350);
DISPLAY 0.680851 (5075 350);
DISPLAY INVISIBLE (5075 350);
FORCEPROP 1 LAST COMMENT_BODY TRUE
J 0
(4730 205);
DISPLAY 0.872340 (4730 205);
PAINT GREEN (4730 205);
DISPLAY INVISIBLE (4730 205);
FORCEPROP 1 LAST OFFPAGE TRUE
J 0
(5100 175);
DISPLAY 0.872340 (5100 175);
DISPLAY INVISIBLE (5100 175);
FORCEPROP 2 LAST CDS_LIB standard
J 0
(4775 300);
DISPLAY INVISIBLE (4775 300);
FORCEADD UNIVERSAL_GND..1
(4650 -1175);
FORCEPROP 3 LASTPIN (4650 -1125) SIG_NAME GND\g
J 0
(4660 -1115);
DISPLAY 0.659574 (4660 -1115);
PAINT MONO (4660 -1115);
DISPLAY INVISIBLE (4660 -1115);
FORCEPROP 2 LAST CDS_LIB logical_power
J 0
(4650 -1175);
DISPLAY INVISIBLE (4650 -1175);
FORCEPROP 1 LAST HDL_POWER GND
J 1
(4675 -1250);
DISPLAY 0.702128 (4675 -1250);
PAINT GREEN (4675 -1250);
DISPLAY INVISIBLE (4675 -1250);
FORCEPROP 1 LAST PATH I159
J 0
(4725 -1175);
DISPLAY 0.872340 (4725 -1175);
PAINT AQUA (4725 -1175);
DISPLAY INVISIBLE (4725 -1175);
FORCEADD UNIVERSAL_POWER..1
(2725 1025);
FORCEPROP 3 LASTPIN (2725 975) SIG_NAME P3V3_AUX\g
J 0
(2735 985);
DISPLAY 0.659574 (2735 985);
PAINT MONO (2735 985);
DISPLAY INVISIBLE (2735 985);
FORCEPROP 1 LAST HDL_POWER P3V3_AUX
J 1
(2725 1075);
DISPLAY 0.702128 (2725 1075);
PAINT PEACH (2725 1075);
FORCEPROP 2 LAST CDS_LIB logical_power
J 0
(2725 1025);
DISPLAY INVISIBLE (2725 1025);
FORCEPROP 1 LAST PATH I160
J 0
(2775 1050);
DISPLAY 0.872340 (2775 1050);
PAINT AQUA (2775 1050);
DISPLAY INVISIBLE (2775 1050);
FORCEADD Q_RES..1
R 2
(3800 300);
FORCEPROP 1 LAST VALUE 0
J 0
(3850 275);
DISPLAY 0.510638 (3850 275);
PAINT SKYBLUE (3850 275);
FORCEPROP 1 LAST TOLERANCE 5%
J 2
(3950 275);
DISPLAY 0.510638 (3950 275);
PAINT SKYBLUE (3950 275);
FORCEPROP 1 LAST MATERIAL CHIP
J 2
(4075 275);
DISPLAY 0.510638 (4075 275);
PAINT SKYBLUE (4075 275);
FORCEPROP 1 LAST WATTAGE 1/16W
J 0
(4100 275);
DISPLAY 0.510638 (4100 275);
PAINT SKYBLUE (4100 275);
FORCEPROP 1 LAST PACK_TYPE 0402LF
J 2
(4400 275);
DISPLAY 0.510638 (4400 275);
PAINT SKYBLUE (4400 275);
FORCEPROP 2 LAST CDS_LIB pure_quanta
J 0
(3800 300);
DISPLAY INVISIBLE (3800 300);
FORCEPROP 1 LAST PATH I161
J 2
(3850 450);
DISPLAY 0.978723 (3850 450);
PAINT WHITE (3850 450);
DISPLAY INVISIBLE (3850 450);
FORCEPROP 1 LAST PART_NUMBER CS00002JB13
J 2
(4050 325);
DISPLAY 0.510638 (4050 325);
PAINT WHITE (4050 325);
DISPLAY INVISIBLE (4050 325);
FORCEPROP 1 LAST LOCATION R626
J 2
(3750 300);
DISPLAY 0.702128 (3750 300);
PAINT YELLOW (3750 300);
FORCEPROP 0 LAST $SEC 1
J 0
(3750 350);
DISPLAY 0.680851 (3750 350);
PAINT MONO (3750 350);
DISPLAY INVISIBLE (3750 350);
FORCEPROP 0 LAST CDS_SEC 1
J 0
(3750 350);
DISPLAY 1.021277 (3750 350);
DISPLAY INVISIBLE (3750 350);
FORCEPROP 1 LASTPIN (3900 300) $PN 1
J 2
(3888 312);
DISPLAY 0.808511 (3888 312);
PAINT WHITE (3888 312);
DISPLAY INVISIBLE (3888 312);
FORCEPROP 1 LASTPIN (3700 300) $PN 2
J 2
(3738 312);
DISPLAY 0.808511 (3738 312);
PAINT WHITE (3738 312);
DISPLAY INVISIBLE (3738 312);
FORCEADD Q_RES..2
(2725 700);
FORCEPROP 1 LAST TOLERANCE 1%
J 0
(2770 725);
DISPLAY 0.978723 (2770 725);
FORCEPROP 1 LAST WATTAGE 1/16W
J 0
(2765 675);
DISPLAY 0.978723 (2765 675);
FORCEPROP 1 LAST MATERIAL CHIP
J 0
(2765 625);
DISPLAY 0.978723 (2765 625);
FORCEPROP 1 LAST PACK_TYPE 0402LF
J 0
(2765 525);
DISPLAY 0.978723 (2765 525);
FORCEPROP 1 LAST VALUE 1K
J 0
(2770 775);
DISPLAY 0.978723 (2770 775);
FORCEPROP 1 LAST PART_NUMBER CS21002FB06
J 0
(2765 575);
DISPLAY 0.978723 (2765 575);
FORCEPROP 2 LAST CDS_LIB pure_quanta
J 0
(2725 700);
DISPLAY INVISIBLE (2725 700);
FORCEPROP 1 LAST PATH I162
J 0
(2775 875);
DISPLAY 0.978723 (2775 875);
PAINT WHITE (2775 875);
DISPLAY INVISIBLE (2775 875);
FORCEPROP 1 LAST LOCATION R736
J 0
(2770 825);
DISPLAY 0.978723 (2770 825);
FORCEPROP 1 LASTPIN (2725 800) $PN 1
J 0
(2730 762);
DISPLAY 0.787234 (2730 762);
PAINT MONO (2730 762);
FORCEPROP 1 LASTPIN (2725 600) $PN 2
J 0
(2730 610);
DISPLAY 0.787234 (2730 610);
PAINT MONO (2730 610);
FORCEPROP 0 LAST $SEC 1
J 0
(2775 875);
DISPLAY 0.680851 (2775 875);
PAINT MONO (2775 875);
DISPLAY INVISIBLE (2775 875);
FORCEPROP 0 LAST CDS_SEC 1
J 0
(2775 875);
DISPLAY 0.680851 (2775 875);
DISPLAY INVISIBLE (2775 875);
FORCEADD 2N7002A7..1
(4050 -625);
FORCEPROP 1 LAST MATERIAL IC
J 0
(3753 -295);
DISPLAY 0.723404 (3753 -295);
PAINT GREEN (3753 -295);
FORCEPROP 2 LAST PART_TYPE SMLF
J 0
(3775 -100);
DISPLAY 0.680851 (3775 -100);
FORCEPROP 2 LAST VALUE 2N7002A-7
J 0
(3775 -150);
DISPLAY 0.680851 (3775 -150);
FORCEPROP 1 LAST PART_NUMBER BAM70020068
J 0
(3753 -240);
DISPLAY 0.723404 (3753 -240);
PAINT GREEN (3753 -240);
FORCEPROP 1 LAST CDS_LMAN_SYM_OUTLINE -300,325,300,-325
J 0
(4050 -625);
DISPLAY 0.468085 (4050 -625);
PAINT GREEN (4050 -625);
DISPLAY INVISIBLE (4050 -625);
FORCEPROP 1 LAST NEEDS_NO_SIZE TRUE
J 0
(4050 -625);
DISPLAY 0.723404 (4050 -625);
PAINT GREEN (4050 -625);
DISPLAY INVISIBLE (4050 -625);
FORCEPROP 2 LAST CDS_LIB pure_quanta
J 0
(4050 -625);
DISPLAY INVISIBLE (4050 -625);
FORCEPROP 1 LAST PATH I163
J 0
(4050 -625);
DISPLAY 0.723404 (4050 -625);
PAINT GREEN (4050 -625);
DISPLAY INVISIBLE (4050 -625);
FORCEPROP 1 LAST LOCATION Q8
J 0
(3753 -190);
DISPLAY 0.723404 (3753 -190);
PAINT GREEN (3753 -190);
FORCEPROP 0 LASTPIN (3600 -350) $PN D
J 2
(3590 -340);
DISPLAY 0.680851 (3590 -340);
PAINT MONO (3590 -340);
FORCEPROP 0 LASTPIN (3600 -600) $PN G
J 2
(3590 -590);
DISPLAY 0.680851 (3590 -590);
PAINT MONO (3590 -590);
FORCEPROP 0 LASTPIN (4500 -850) $PN S
J 0
(4510 -840);
DISPLAY 0.680851 (4510 -840);
PAINT MONO (4510 -840);
FORCEPROP 0 LAST $SEC 1
J 0
(3775 -50);
DISPLAY 0.680851 (3775 -50);
PAINT MONO (3775 -50);
DISPLAY INVISIBLE (3775 -50);
FORCEPROP 0 LAST CDS_SEC 1
J 0
(3775 -50);
DISPLAY 0.680851 (3775 -50);
DISPLAY INVISIBLE (3775 -50);
FORCEADD Q_RES..1
R 2
(2725 -600);
FORCEPROP 1 LAST VALUE 0
J 0
(2775 -625);
DISPLAY 0.510638 (2775 -625);
PAINT SKYBLUE (2775 -625);
FORCEPROP 1 LAST TOLERANCE 5%
J 2
(2875 -625);
DISPLAY 0.510638 (2875 -625);
PAINT SKYBLUE (2875 -625);
FORCEPROP 1 LAST WATTAGE 1/16W
J 0
(3025 -625);
DISPLAY 0.510638 (3025 -625);
PAINT SKYBLUE (3025 -625);
FORCEPROP 1 LAST MATERIAL CHIP
J 2
(3000 -625);
DISPLAY 0.510638 (3000 -625);
PAINT SKYBLUE (3000 -625);
FORCEPROP 1 LAST PACK_TYPE 0402LF
J 2
(3325 -625);
DISPLAY 0.510638 (3325 -625);
PAINT SKYBLUE (3325 -625);
FORCEPROP 2 LAST CDS_LIB pure_quanta
J 0
(2725 -600);
DISPLAY INVISIBLE (2725 -600);
FORCEPROP 1 LAST PATH I164
J 2
(2775 -450);
DISPLAY 0.978723 (2775 -450);
PAINT WHITE (2775 -450);
DISPLAY INVISIBLE (2775 -450);
FORCEPROP 1 LAST PART_NUMBER CS00002JB13
J 2
(2975 -575);
DISPLAY 0.510638 (2975 -575);
PAINT WHITE (2975 -575);
DISPLAY INVISIBLE (2975 -575);
FORCEPROP 1 LAST LOCATION R83
J 2
(2675 -600);
DISPLAY 0.702128 (2675 -600);
PAINT YELLOW (2675 -600);
FORCEPROP 0 LAST $SEC 1
J 0
(2675 -550);
DISPLAY 0.680851 (2675 -550);
PAINT MONO (2675 -550);
DISPLAY INVISIBLE (2675 -550);
FORCEPROP 0 LAST CDS_SEC 1
J 0
(2675 -550);
DISPLAY 1.021277 (2675 -550);
DISPLAY INVISIBLE (2675 -550);
FORCEPROP 1 LASTPIN (2825 -600) $PN 1
J 2
(2813 -588);
DISPLAY 0.808511 (2813 -588);
PAINT WHITE (2813 -588);
DISPLAY INVISIBLE (2813 -588);
FORCEPROP 1 LASTPIN (2625 -600) $PN 2
J 2
(2663 -588);
DISPLAY 0.808511 (2663 -588);
PAINT WHITE (2663 -588);
DISPLAY INVISIBLE (2663 -588);
FORCEADD UNIVERSAL_POWER..1
(2475 175);
FORCEPROP 3 LASTPIN (2475 125) SIG_NAME P3V3_AUX\g
J 0
(2485 135);
DISPLAY 0.659574 (2485 135);
PAINT MONO (2485 135);
DISPLAY INVISIBLE (2485 135);
FORCEPROP 1 LAST HDL_POWER P3V3_AUX
J 1
(2475 225);
DISPLAY 0.702128 (2475 225);
PAINT PEACH (2475 225);
FORCEPROP 2 LAST CDS_LIB logical_power
J 0
(2475 175);
DISPLAY INVISIBLE (2475 175);
FORCEPROP 1 LAST PATH I165
J 0
(2525 200);
DISPLAY 0.872340 (2525 200);
PAINT AQUA (2525 200);
DISPLAY INVISIBLE (2525 200);
FORCEADD Q_RES..2
R 2
(2475 -150);
FORCEPROP 1 LAST MATERIAL CHIP
J 2
(2435 -225);
DISPLAY 0.978723 (2435 -225);
FORCEPROP 1 LAST PACK_TYPE 0402LF
J 2
(2435 -325);
DISPLAY 0.978723 (2435 -325);
FORCEPROP 1 LAST PART_NUMBER CS21002FB06
J 2
(2435 -275);
DISPLAY 0.978723 (2435 -275);
FORCEPROP 1 LAST VALUE 1K
J 2
(2430 -75);
DISPLAY 0.978723 (2430 -75);
FORCEPROP 1 LAST TOLERANCE 1%
J 2
(2430 -125);
DISPLAY 0.978723 (2430 -125);
FORCEPROP 1 LAST WATTAGE 1/16W
J 2
(2435 -175);
DISPLAY 0.978723 (2435 -175);
FORCEPROP 2 LAST CDS_LIB pure_quanta
J 2
(2475 -150);
DISPLAY INVISIBLE (2475 -150);
FORCEPROP 1 LAST PATH I166
J 2
(2425 25);
DISPLAY 0.978723 (2425 25);
PAINT WHITE (2425 25);
DISPLAY INVISIBLE (2425 25);
FORCEPROP 1 LAST LOCATION R735
J 2
(2430 -25);
DISPLAY 0.978723 (2430 -25);
FORCEPROP 1 LASTPIN (2475 -50) $PN 1
J 2
(2470 -88);
DISPLAY 0.787234 (2470 -88);
PAINT MONO (2470 -88);
FORCEPROP 1 LASTPIN (2475 -250) $PN 2
J 2
(2470 -240);
DISPLAY 0.787234 (2470 -240);
PAINT MONO (2470 -240);
FORCEPROP 0 LAST $SEC 1
J 0
(2450 25);
DISPLAY 0.680851 (2450 25);
PAINT MONO (2450 25);
DISPLAY INVISIBLE (2450 25);
FORCEPROP 0 LAST CDS_SEC 1
J 0
(2450 25);
DISPLAY 0.680851 (2450 25);
DISPLAY INVISIBLE (2450 25);
FORCEADD OFFPAGE..1
(1675 -600);
FORCEPROP 2 LAST $XR0 28 
J 0
(1454 -600);
DISPLAY 0.638298 (1454 -600);
PAINT MONO (1454 -600);
FORCEPROP 2 LAST CDS_LIB standard
J 0
(1675 -600);
PAINT MONO (1675 -600);
DISPLAY INVISIBLE (1675 -600);
FORCEPROP 1 LAST OFFPAGE TRUE
J 0
(2000 -725);
DISPLAY 0.872340 (2000 -725);
DISPLAY INVISIBLE (2000 -725);
FORCEPROP 1 LAST COMMENT_BODY TRUE
J 0
(1800 -700);
DISPLAY 0.872340 (1800 -700);
PAINT GREEN (1800 -700);
DISPLAY INVISIBLE (1800 -700);
FORCEPROP 2 LAST PATH I167
J 0
(1475 -550);
DISPLAY 0.680851 (1475 -550);
DISPLAY INVISIBLE (1475 -550);
FORCEADD Q_RES..2
(-3250 875);
FORCEPROP 1 LAST WATTAGE 1/16W
J 0
(-3210 850);
DISPLAY 0.510638 (-3210 850);
PAINT SKYBLUE (-3210 850);
FORCEPROP 1 LAST MATERIAL CHIP
J 0
(-3210 800);
DISPLAY 0.510638 (-3210 800);
PAINT SKYBLUE (-3210 800);
FORCEPROP 1 LAST VALUE 4.7K
J 0
(-3205 950);
DISPLAY 0.510638 (-3205 950);
PAINT SKYBLUE (-3205 950);
FORCEPROP 1 LAST TOLERANCE 1%
J 0
(-3205 900);
DISPLAY 0.510638 (-3205 900);
PAINT SKYBLUE (-3205 900);
FORCEPROP 1 LAST PACK_TYPE 0402LF
J 0
(-3210 700);
DISPLAY 0.510638 (-3210 700);
PAINT SKYBLUE (-3210 700);
FORCEPROP 1 LAST PART_NUMBER CS24702FB06
J 0
(-3210 750);
DISPLAY 0.510638 (-3210 750);
PAINT WHITE (-3210 750);
FORCEPROP 2 LAST CDS_LIB pure_quanta
J 0
(-3250 875);
DISPLAY INVISIBLE (-3250 875);
FORCEPROP 2 LAST SEC_TYPE 0402LF
J 0
(-3200 1100);
DISPLAY 0.680851 (-3200 1100);
DISPLAY INVISIBLE (-3200 1100);
FORCEPROP 1 LAST PATH I168
J 0
(-3200 1050);
DISPLAY 0.978723 (-3200 1050);
PAINT WHITE (-3200 1050);
DISPLAY INVISIBLE (-3200 1050);
FORCEPROP 1 LAST LOCATION R740
J 0
(-3205 1000);
DISPLAY 0.702128 (-3205 1000);
PAINT YELLOW (-3205 1000);
FORCEPROP 1 LASTPIN (-3250 975) $PN 1
J 0
(-3245 937);
DISPLAY 0.808511 (-3245 937);
PAINT WHITE (-3245 937);
FORCEPROP 1 LASTPIN (-3250 775) $PN 2
J 0
(-3245 785);
DISPLAY 0.808511 (-3245 785);
PAINT WHITE (-3245 785);
FORCEPROP 2 LAST SEC 1
J 0
(-3200 1100);
DISPLAY 0.680851 (-3200 1100);
PAINT MONO (-3200 1100);
DISPLAY INVISIBLE (-3200 1100);
FORCEADD Q_RES..2
(-3600 875);
FORCEPROP 1 LAST MATERIAL CHIP
J 0
(-3550 850);
DISPLAY 0.510638 (-3550 850);
PAINT SKYBLUE (-3550 850);
FORCEPROP 1 LAST PACK_TYPE 0402LF
J 0
(-3550 825);
DISPLAY 0.510638 (-3550 825);
PAINT SKYBLUE (-3550 825);
FORCEPROP 1 LAST WATTAGE 1/16W
J 0
(-3550 775);
DISPLAY 0.510638 (-3550 775);
PAINT SKYBLUE (-3550 775);
FORCEPROP 1 LAST VALUE 4.7K
J 0
(-3555 950);
DISPLAY 0.510638 (-3555 950);
PAINT SKYBLUE (-3555 950);
FORCEPROP 1 LAST TOLERANCE 1%
J 0
(-3555 900);
DISPLAY 0.510638 (-3555 900);
PAINT SKYBLUE (-3555 900);
FORCEPROP 2 LAST CDS_LIB pure_quanta
J 0
(-3600 875);
DISPLAY INVISIBLE (-3600 875);
FORCEPROP 2 LAST SEC_TYPE 0402LF
J 0
(-3550 1100);
DISPLAY 0.680851 (-3550 1100);
DISPLAY INVISIBLE (-3550 1100);
FORCEPROP 1 LAST PATH I169
J 0
(-3550 1050);
DISPLAY 0.978723 (-3550 1050);
PAINT WHITE (-3550 1050);
DISPLAY INVISIBLE (-3550 1050);
FORCEPROP 1 LAST PART_NUMBER CS24702FB06
J 0
(-3560 750);
DISPLAY 0.510638 (-3560 750);
PAINT WHITE (-3560 750);
DISPLAY INVISIBLE (-3560 750);
FORCEPROP 1 LAST LOCATION R739
J 0
(-3555 1000);
DISPLAY 0.702128 (-3555 1000);
PAINT YELLOW (-3555 1000);
FORCEPROP 1 LASTPIN (-3600 975) $PN 1
J 0
(-3595 937);
DISPLAY 0.808511 (-3595 937);
PAINT WHITE (-3595 937);
FORCEPROP 1 LASTPIN (-3600 775) $PN 2
J 0
(-3595 785);
DISPLAY 0.808511 (-3595 785);
PAINT WHITE (-3595 785);
FORCEPROP 2 LAST SEC 1
J 0
(-3550 1100);
DISPLAY 0.680851 (-3550 1100);
PAINT MONO (-3550 1100);
DISPLAY INVISIBLE (-3550 1100);
FORCEADD UNIVERSAL_POWER..1
(-3950 1350);
FORCEPROP 3 LASTPIN (-3950 1300) SIG_NAME P3V3_AUX\g
J 0
(-3940 1310);
DISPLAY 0.659574 (-3940 1310);
PAINT MONO (-3940 1310);
DISPLAY INVISIBLE (-3940 1310);
FORCEPROP 1 LAST HDL_POWER P3V3_AUX
J 1
(-3950 1400);
DISPLAY 0.702128 (-3950 1400);
PAINT GREEN (-3950 1400);
FORCEPROP 2 LAST CDS_LIB logical_power
J 0
(-3950 1350);
DISPLAY INVISIBLE (-3950 1350);
FORCEPROP 1 LAST PATH I170
J 0
(-3900 1375);
DISPLAY 0.872340 (-3900 1375);
PAINT AQUA (-3900 1375);
DISPLAY INVISIBLE (-3900 1375);
FORCEADD Q_RES..2
(-3950 875);
FORCEPROP 1 LAST VALUE 4.7K
J 0
(-3900 950);
DISPLAY 0.510638 (-3900 950);
PAINT SKYBLUE (-3900 950);
FORCEPROP 1 LAST WATTAGE 1/16W
J 0
(-3900 750);
DISPLAY 0.510638 (-3900 750);
PAINT SKYBLUE (-3900 750);
FORCEPROP 1 LAST PACK_TYPE 0402LF
J 0
(-3900 850);
DISPLAY 0.510638 (-3900 850);
PAINT SKYBLUE (-3900 850);
FORCEPROP 1 LAST TOLERANCE 1%
J 0
(-3900 900);
DISPLAY 0.510638 (-3900 900);
PAINT SKYBLUE (-3900 900);
FORCEPROP 1 LAST MATERIAL CHIP
J 0
(-3905 800);
DISPLAY 0.510638 (-3905 800);
PAINT SKYBLUE (-3905 800);
FORCEPROP 2 LAST CDS_LIB pure_quanta
J 0
(-3950 875);
DISPLAY INVISIBLE (-3950 875);
FORCEPROP 2 LAST SEC_TYPE 0402LF
J 0
(-3900 1100);
DISPLAY 0.680851 (-3900 1100);
DISPLAY INVISIBLE (-3900 1100);
FORCEPROP 1 LAST PATH I171
J 0
(-3900 1050);
DISPLAY 0.978723 (-3900 1050);
PAINT WHITE (-3900 1050);
DISPLAY INVISIBLE (-3900 1050);
FORCEPROP 1 LAST PART_NUMBER CS24702FB06
J 0
(-3905 750);
DISPLAY 0.510638 (-3905 750);
PAINT WHITE (-3905 750);
DISPLAY INVISIBLE (-3905 750);
FORCEPROP 1 LAST LOCATION R738
J 0
(-3905 1000);
DISPLAY 0.702128 (-3905 1000);
PAINT YELLOW (-3905 1000);
FORCEPROP 1 LASTPIN (-3950 975) $PN 1
J 0
(-3945 937);
DISPLAY 0.808511 (-3945 937);
PAINT WHITE (-3945 937);
FORCEPROP 1 LASTPIN (-3950 775) $PN 2
J 0
(-3945 785);
DISPLAY 0.808511 (-3945 785);
PAINT WHITE (-3945 785);
FORCEPROP 2 LAST SEC 1
J 0
(-3900 1100);
DISPLAY 0.680851 (-3900 1100);
PAINT MONO (-3900 1100);
DISPLAY INVISIBLE (-3900 1100);
FORCEADD Q_RES..2
(-3250 200);
FORCEPROP 1 LAST MATERIAL EMPTY
J 0
(-3210 125);
DISPLAY 0.510638 (-3210 125);
PAINT RED (-3210 125);
FORCEPROP 1 LAST VALUE 100
J 0
(-3205 275);
DISPLAY 0.510638 (-3205 275);
PAINT SKYBLUE (-3205 275);
FORCEPROP 1 LAST WATTAGE 1/16W
J 0
(-3210 175);
DISPLAY 0.510638 (-3210 175);
PAINT SKYBLUE (-3210 175);
FORCEPROP 1 LAST PACK_TYPE 0402LF
J 0
(-3210 25);
DISPLAY 0.510638 (-3210 25);
PAINT SKYBLUE (-3210 25);
FORCEPROP 1 LAST PART_NUMBER CS11002FB07
J 0
(-3210 75);
DISPLAY 0.510638 (-3210 75);
PAINT WHITE (-3210 75);
FORCEPROP 1 LAST TOLERANCE 1%
J 0
(-3205 225);
DISPLAY 0.510638 (-3205 225);
PAINT SKYBLUE (-3205 225);
FORCEPROP 2 LAST CDS_LIB pure_quanta
J 0
(-3250 200);
DISPLAY INVISIBLE (-3250 200);
FORCEPROP 1 LAST PATH I172
J 0
(-3200 375);
DISPLAY 0.978723 (-3200 375);
PAINT WHITE (-3200 375);
DISPLAY INVISIBLE (-3200 375);
FORCEPROP 1 LAST LOCATION R745
J 0
(-3205 325);
DISPLAY 0.702128 (-3205 325);
PAINT YELLOW (-3205 325);
FORCEPROP 1 LASTPIN (-3250 300) $PN 1
J 0
(-3245 262);
DISPLAY 0.808511 (-3245 262);
PAINT WHITE (-3245 262);
FORCEPROP 1 LASTPIN (-3250 100) $PN 2
J 0
(-3245 110);
DISPLAY 0.808511 (-3245 110);
PAINT WHITE (-3245 110);
FORCEPROP 0 LAST $SEC 1
J 0
(-3200 375);
DISPLAY 0.680851 (-3200 375);
PAINT MONO (-3200 375);
DISPLAY INVISIBLE (-3200 375);
FORCEPROP 0 LAST CDS_SEC 1
J 0
(-3200 375);
DISPLAY 1.021277 (-3200 375);
DISPLAY INVISIBLE (-3200 375);
FORCEADD Q_RES..2
(-3600 200);
FORCEPROP 1 LAST MATERIAL EMPTY
J 0
(-3560 125);
DISPLAY 0.510638 (-3560 125);
PAINT RED (-3560 125);
FORCEPROP 1 LAST WATTAGE 1/16W
J 0
(-3560 175);
DISPLAY 0.510638 (-3560 175);
PAINT SKYBLUE (-3560 175);
FORCEPROP 1 LAST VALUE 100
J 0
(-3555 275);
DISPLAY 0.510638 (-3555 275);
PAINT SKYBLUE (-3555 275);
FORCEPROP 1 LAST TOLERANCE 1%
J 0
(-3555 225);
DISPLAY 0.510638 (-3555 225);
PAINT SKYBLUE (-3555 225);
FORCEPROP 1 LAST PACK_TYPE 0402LF
J 0
(-3550 75);
DISPLAY 0.510638 (-3550 75);
PAINT SKYBLUE (-3550 75);
FORCEPROP 2 LAST CDS_LIB pure_quanta
J 0
(-3600 200);
DISPLAY INVISIBLE (-3600 200);
FORCEPROP 1 LAST PATH I173
J 0
(-3550 375);
DISPLAY 0.978723 (-3550 375);
PAINT WHITE (-3550 375);
DISPLAY INVISIBLE (-3550 375);
FORCEPROP 1 LAST PART_NUMBER CS11002FB07
J 0
(-3560 75);
DISPLAY 0.510638 (-3560 75);
PAINT WHITE (-3560 75);
DISPLAY INVISIBLE (-3560 75);
FORCEPROP 1 LAST LOCATION R744
J 0
(-3555 325);
DISPLAY 0.702128 (-3555 325);
PAINT YELLOW (-3555 325);
FORCEPROP 1 LASTPIN (-3600 300) $PN 1
J 0
(-3595 262);
DISPLAY 0.808511 (-3595 262);
PAINT WHITE (-3595 262);
FORCEPROP 1 LASTPIN (-3600 100) $PN 2
J 0
(-3595 110);
DISPLAY 0.808511 (-3595 110);
PAINT WHITE (-3595 110);
FORCEPROP 0 LAST $SEC 1
J 0
(-3550 375);
DISPLAY 0.680851 (-3550 375);
PAINT MONO (-3550 375);
DISPLAY INVISIBLE (-3550 375);
FORCEPROP 0 LAST CDS_SEC 1
J 0
(-3550 375);
DISPLAY 1.021277 (-3550 375);
DISPLAY INVISIBLE (-3550 375);
FORCEADD UNIVERSAL_GND..1
(-3800 -275);
FORCEPROP 3 LASTPIN (-3800 -225) SIG_NAME GND\g
J 0
(-3790 -215);
DISPLAY 0.659574 (-3790 -215);
PAINT MONO (-3790 -215);
DISPLAY INVISIBLE (-3790 -215);
FORCEPROP 2 LAST CDS_LIB logical_power
J 0
(-3800 -275);
DISPLAY INVISIBLE (-3800 -275);
FORCEPROP 1 LAST HDL_POWER GND
J 1
(-3775 -350);
DISPLAY 0.702128 (-3775 -350);
PAINT GREEN (-3775 -350);
DISPLAY INVISIBLE (-3775 -350);
FORCEPROP 1 LAST PATH I174
J 0
(-3725 -275);
DISPLAY 0.872340 (-3725 -275);
PAINT AQUA (-3725 -275);
DISPLAY INVISIBLE (-3725 -275);
FORCEADD Q_RES..2
(-3950 200);
FORCEPROP 1 LAST VALUE 100
J 0
(-3905 275);
DISPLAY 0.510638 (-3905 275);
PAINT SKYBLUE (-3905 275);
FORCEPROP 1 LAST MATERIAL EMPTY
J 0
(-3910 125);
DISPLAY 0.510638 (-3910 125);
PAINT RED (-3910 125);
FORCEPROP 1 LAST TOLERANCE 1%
J 0
(-3905 225);
DISPLAY 0.510638 (-3905 225);
PAINT SKYBLUE (-3905 225);
FORCEPROP 1 LAST WATTAGE 1/16W
J 0
(-3910 175);
DISPLAY 0.510638 (-3910 175);
PAINT SKYBLUE (-3910 175);
FORCEPROP 1 LAST PACK_TYPE 0402LF
J 0
(-3925 75);
DISPLAY 0.510638 (-3925 75);
PAINT SKYBLUE (-3925 75);
FORCEPROP 2 LAST CDS_LIB pure_quanta
J 0
(-3950 200);
DISPLAY INVISIBLE (-3950 200);
FORCEPROP 1 LAST PATH I175
J 0
(-3900 375);
DISPLAY 0.978723 (-3900 375);
PAINT WHITE (-3900 375);
DISPLAY INVISIBLE (-3900 375);
FORCEPROP 1 LAST PART_NUMBER CS11002FB07
J 0
(-3910 75);
DISPLAY 0.510638 (-3910 75);
PAINT WHITE (-3910 75);
DISPLAY INVISIBLE (-3910 75);
FORCEPROP 1 LAST LOCATION R743
J 0
(-3905 325);
DISPLAY 0.702128 (-3905 325);
PAINT YELLOW (-3905 325);
FORCEPROP 1 LASTPIN (-3950 300) $PN 1
J 0
(-3945 262);
DISPLAY 0.808511 (-3945 262);
PAINT WHITE (-3945 262);
FORCEPROP 1 LASTPIN (-3950 100) $PN 2
J 0
(-3945 110);
DISPLAY 0.808511 (-3945 110);
PAINT WHITE (-3945 110);
FORCEPROP 0 LAST $SEC 1
J 0
(-3900 375);
DISPLAY 0.680851 (-3900 375);
PAINT MONO (-3900 375);
DISPLAY INVISIBLE (-3900 375);
FORCEPROP 0 LAST CDS_SEC 1
J 0
(-3900 375);
DISPLAY 1.021277 (-3900 375);
DISPLAY INVISIBLE (-3900 375);
FORCEADD OFFPAGE..2
(-2175 550);
FORCEPROP 2 LAST $XR0 28 
J 0
(-1986 550);
DISPLAY 0.638298 (-1986 550);
PAINT MONO (-1986 550);
FORCEPROP 2 LAST CDS_LIB standard
J 0
(-2175 550);
DISPLAY INVISIBLE (-2175 550);
FORCEPROP 1 LAST OFFPAGE TRUE
J 0
(-1850 425);
DISPLAY 0.872340 (-1850 425);
DISPLAY INVISIBLE (-1850 425);
FORCEPROP 1 LAST COMMENT_BODY TRUE
J 0
(-2220 455);
DISPLAY 0.872340 (-2220 455);
PAINT GREEN (-2220 455);
DISPLAY INVISIBLE (-2220 455);
FORCEPROP 2 LAST PATH I176
J 0
(-2000 625);
DISPLAY 0.680851 (-2000 625);
DISPLAY INVISIBLE (-2000 625);
FORCEADD OFFPAGE..2
(-2175 500);
FORCEPROP 2 LAST $XR0 28 
J 0
(-1986 500);
DISPLAY 0.638298 (-1986 500);
PAINT MONO (-1986 500);
FORCEPROP 2 LAST CDS_LIB standard
J 0
(-2175 500);
DISPLAY INVISIBLE (-2175 500);
FORCEPROP 1 LAST OFFPAGE TRUE
J 0
(-1850 375);
DISPLAY 0.872340 (-1850 375);
DISPLAY INVISIBLE (-1850 375);
FORCEPROP 1 LAST COMMENT_BODY TRUE
J 0
(-2220 405);
DISPLAY 0.872340 (-2220 405);
PAINT GREEN (-2220 405);
DISPLAY INVISIBLE (-2220 405);
FORCEPROP 2 LAST PATH I177
J 0
(-2000 575);
DISPLAY 0.680851 (-2000 575);
DISPLAY INVISIBLE (-2000 575);
FORCEADD OFFPAGE..2
(-2175 450);
FORCEPROP 2 LAST $XR0 28 
J 0
(-1986 450);
DISPLAY 0.638298 (-1986 450);
PAINT MONO (-1986 450);
FORCEPROP 2 LAST CDS_LIB standard
J 0
(-2175 450);
DISPLAY INVISIBLE (-2175 450);
FORCEPROP 1 LAST OFFPAGE TRUE
J 0
(-1850 325);
DISPLAY 0.872340 (-1850 325);
DISPLAY INVISIBLE (-1850 325);
FORCEPROP 1 LAST COMMENT_BODY TRUE
J 0
(-2220 355);
DISPLAY 0.872340 (-2220 355);
PAINT GREEN (-2220 355);
DISPLAY INVISIBLE (-2220 355);
FORCEPROP 2 LAST PATH I178
J 0
(-2000 525);
DISPLAY 0.680851 (-2000 525);
DISPLAY INVISIBLE (-2000 525);
FORCEADD NCP380HSNAJAAT1G..1
(-50 1250);
FORCEPROP 2 LAST PART_TYPE SMLF
J 0
(-250 1625);
DISPLAY 0.680851 (-250 1625);
FORCEPROP 2 LAST VALUE NCP380HSNAJAAT1G
J 0
(-250 1575);
DISPLAY 0.680851 (-250 1575);
FORCEPROP 1 LAST PART_NUMBER AL000380K00
J 0
(-269 1484);
DISPLAY 0.723404 (-269 1484);
PAINT GREEN (-269 1484);
FORCEPROP 1 LAST MATERIAL IC
J 0
(-269 1357);
DISPLAY 0.723404 (-269 1357);
PAINT GREEN (-269 1357);
FORCEPROP 2 LAST CDS_LIB pure_quanta
J 0
(-50 1250);
DISPLAY INVISIBLE (-50 1250);
FORCEPROP 1 LAST PATH I179
J 0
(-50 1250);
DISPLAY 0.723404 (-50 1250);
PAINT GREEN (-50 1250);
DISPLAY INVISIBLE (-50 1250);
FORCEPROP 1 LAST NEEDS_NO_SIZE TRUE
J 0
(-50 1250);
DISPLAY 0.723404 (-50 1250);
PAINT GREEN (-50 1250);
DISPLAY INVISIBLE (-50 1250);
FORCEPROP 1 LAST CDS_LMAN_SYM_OUTLINE -225,100,225,-100
J 0
(-50 1250);
DISPLAY 0.468085 (-50 1250);
PAINT GREEN (-50 1250);
DISPLAY INVISIBLE (-50 1250);
FORCEPROP 2 LAST SEC_TYPE 
J 0
(-250 1775);
DISPLAY 0.680851 (-250 1775);
DISPLAY INVISIBLE (-250 1775);
FORCEPROP 1 LAST LOCATION U10
J 0
(-269 1531);
DISPLAY 0.723404 (-269 1531);
PAINT GREEN (-269 1531);
FORCEPROP 0 LASTPIN (-425 1250) $PN 3
J 2
(-435 1260);
DISPLAY 0.680851 (-435 1260);
PAINT MONO (-435 1260);
FORCEPROP 0 LASTPIN (325 1250) $PN 4
J 0
(335 1260);
DISPLAY 0.680851 (335 1260);
PAINT MONO (335 1260);
FORCEPROP 0 LASTPIN (325 1200) $PN 2
J 0
(335 1210);
DISPLAY 0.680851 (335 1210);
PAINT MONO (335 1210);
FORCEPROP 0 LASTPIN (-425 1200) $PN 5
J 2
(-435 1210);
DISPLAY 0.680851 (-435 1210);
PAINT MONO (-435 1210);
FORCEPROP 0 LASTPIN (-425 1300) $PN 1
J 2
(-435 1310);
DISPLAY 0.680851 (-435 1310);
PAINT MONO (-435 1310);
FORCEPROP 0 LASTPIN (325 1300) $PN 6
J 0
(335 1310);
DISPLAY 0.680851 (335 1310);
PAINT MONO (335 1310);
FORCEPROP 2 LAST SEC 1
J 0
(-250 1775);
DISPLAY 0.680851 (-250 1775);
PAINT MONO (-250 1775);
DISPLAY INVISIBLE (-250 1775);
FORCEADD 74LVC1G07W57..1
(-2450 3475);
FORCEPROP 1 LAST PART_NUMBER ALVC1G07001
J 0
(-2588 3715);
DISPLAY 0.723404 (-2588 3715);
PAINT GREEN (-2588 3715);
FORCEPROP 2 LAST PART_TYPE SMLF
J 0
(-2575 3850);
DISPLAY 0.680851 (-2575 3850);
FORCEPROP 2 LAST VALUE 74LVC1G07W5-7
J 0
(-2575 3800);
DISPLAY 0.680851 (-2575 3800);
FORCEPROP 1 LAST MATERIAL IC
J 0
(-2569 3657);
DISPLAY 0.723404 (-2569 3657);
PAINT GREEN (-2569 3657);
FORCEPROP 2 LAST CDS_LIB pure_quanta
J 0
(-2450 3475);
DISPLAY INVISIBLE (-2450 3475);
FORCEPROP 1 LAST PATH I180
J 0
(-2450 3475);
DISPLAY 0.723404 (-2450 3475);
PAINT GREEN (-2450 3475);
DISPLAY INVISIBLE (-2450 3475);
FORCEPROP 1 LAST NEEDS_NO_SIZE TRUE
J 0
(-2450 3475);
DISPLAY 0.723404 (-2450 3475);
PAINT GREEN (-2450 3475);
DISPLAY INVISIBLE (-2450 3475);
FORCEPROP 1 LAST CDS_LMAN_SYM_OUTLINE -125,150,125,-150
J 0
(-2450 3475);
DISPLAY 0.468085 (-2450 3475);
PAINT GREEN (-2450 3475);
DISPLAY INVISIBLE (-2450 3475);
FORCEPROP 1 LAST LOCATION U23
J 0
(-2594 3756);
DISPLAY 0.723404 (-2594 3756);
PAINT GREEN (-2594 3756);
FORCEPROP 0 LASTPIN (-2725 3475) $PN 2
J 2
(-2735 3485);
DISPLAY 0.680851 (-2735 3485);
PAINT MONO (-2735 3485);
FORCEPROP 0 LASTPIN (-2725 3375) $PN 3
J 2
(-2735 3385);
DISPLAY 0.680851 (-2735 3385);
PAINT MONO (-2735 3385);
FORCEPROP 0 LASTPIN (-2725 3575) $PN 1
J 2
(-2735 3585);
DISPLAY 0.680851 (-2735 3585);
PAINT MONO (-2735 3585);
FORCEPROP 0 LASTPIN (-2175 3575) $PN 5
J 0
(-2165 3585);
DISPLAY 0.680851 (-2165 3585);
PAINT MONO (-2165 3585);
FORCEPROP 0 LASTPIN (-2175 3375) $PN 4
J 0
(-2165 3385);
DISPLAY 0.680851 (-2165 3385);
PAINT MONO (-2165 3385);
FORCEPROP 0 LAST $SEC 1
J 0
(-2575 3900);
DISPLAY 0.680851 (-2575 3900);
PAINT MONO (-2575 3900);
DISPLAY INVISIBLE (-2575 3900);
FORCEPROP 0 LAST CDS_SEC 1
J 0
(-2575 3900);
DISPLAY 0.680851 (-2575 3900);
DISPLAY INVISIBLE (-2575 3900);
FORCEADD Q_CAP..1
(-1975 3700);
FORCEPROP 1 LAST MATERIAL X7R
J 0
(-1925 3600);
DISPLAY 0.978723 (-1925 3600);
FORCEPROP 1 LAST PART_NUMBER CH4104K1B00
J 0
(-1925 3550);
DISPLAY 0.978723 (-1925 3550);
FORCEPROP 1 LAST PACK_TYPE 0402
J 0
(-1925 3500);
DISPLAY 0.978723 (-1925 3500);
FORCEPROP 1 LAST TOLERANCE 10%
J 0
(-1925 3650);
DISPLAY 0.978723 (-1925 3650);
FORCEPROP 1 LAST VALUE 0.1UF
J 0
(-1925 3750);
DISPLAY 0.978723 (-1925 3750);
FORCEPROP 1 LAST VOLTAGE 25V
J 0
(-1925 3700);
DISPLAY 0.978723 (-1925 3700);
FORCEPROP 2 LAST CDS_LIB pure_quanta
J 0
(-1975 3700);
DISPLAY INVISIBLE (-1975 3700);
FORCEPROP 1 LAST PATH I181
J 0
(-1925 3850);
DISPLAY 0.978723 (-1925 3850);
PAINT WHITE (-1925 3850);
DISPLAY INVISIBLE (-1925 3850);
FORCEPROP 1 LAST LOCATION C157
J 0
(-1925 3800);
DISPLAY 0.978723 (-1925 3800);
FORCEPROP 1 LASTPIN (-1975 3800) $PN 1
J 0
(-1965 3780);
DISPLAY 0.787234 (-1965 3780);
PAINT MONO (-1965 3780);
FORCEPROP 1 LASTPIN (-1975 3600) $PN 2
J 0
(-1965 3580);
DISPLAY 0.787234 (-1965 3580);
PAINT MONO (-1965 3580);
FORCEPROP 2 LAST $SEC 1
J 2
(-1925 3900);
DISPLAY 0.680851 (-1925 3900);
PAINT MONO (-1925 3900);
DISPLAY INVISIBLE (-1925 3900);
FORCEPROP 2 LAST CDS_SEC 1
J 2
(-1925 3900);
DISPLAY 1.021277 (-1925 3900);
DISPLAY INVISIBLE (-1925 3900);
FORCEADD UNIVERSAL_GND..1
(-1975 3500);
FORCEPROP 3 LASTPIN (-1975 3550) SIG_NAME GND\g
J 0
(-1965 3560);
DISPLAY 0.659574 (-1965 3560);
PAINT MONO (-1965 3560);
DISPLAY INVISIBLE (-1965 3560);
FORCEPROP 1 LAST HDL_POWER GND
J 1
(-1950 3425);
DISPLAY 0.702128 (-1950 3425);
PAINT GREEN (-1950 3425);
FORCEPROP 1 LAST PATH I182
J 0
(-1900 3500);
DISPLAY 0.872340 (-1900 3500);
PAINT AQUA (-1900 3500);
DISPLAY INVISIBLE (-1900 3500);
FORCEPROP 2 LAST CDS_LIB logical_power
J 0
(-1975 3500);
DISPLAY INVISIBLE (-1975 3500);
FORCEADD Q_RES..1
(3275 2225);
FORCEPROP 1 LAST MATERIAL CHIP
J 2
(3650 2225);
DISPLAY 0.510638 (3650 2225);
PAINT SKYBLUE (3650 2225);
FORCEPROP 1 LAST VALUE 33.2
J 0
(3400 2225);
DISPLAY 0.510638 (3400 2225);
PAINT SKYBLUE (3400 2225);
FORCEPROP 1 LAST PACK_TYPE 0402LF
J 0
(3525 2075);
DISPLAY 0.510638 (3525 2075);
PAINT SKYBLUE (3525 2075);
DISPLAY INVISIBLE (3525 2075);
FORCEPROP 1 LAST WATTAGE 1/16W
J 2
(3250 2075);
DISPLAY 0.510638 (3250 2075);
PAINT SKYBLUE (3250 2075);
DISPLAY INVISIBLE (3250 2075);
FORCEPROP 1 LAST PART_NUMBER CS03322FB03
J 0
(3225 2325);
DISPLAY 0.510638 (3225 2325);
PAINT WHITE (3225 2325);
DISPLAY INVISIBLE (3225 2325);
FORCEPROP 1 LAST TOLERANCE 1%
J 0
(3400 2225);
DISPLAY 0.510638 (3400 2225);
PAINT SKYBLUE (3400 2225);
DISPLAY INVISIBLE (3400 2225);
FORCEPROP 1 LAST PATH I183
J 0
(3225 2375);
DISPLAY 0.978723 (3225 2375);
PAINT WHITE (3225 2375);
DISPLAY INVISIBLE (3225 2375);
FORCEPROP 2 LAST CDS_LIB pure_quanta
J 0
(3275 2225);
DISPLAY INVISIBLE (3275 2225);
FORCEPROP 1 LAST LOCATION R300
J 2
(3175 2225);
DISPLAY 0.702128 (3175 2225);
PAINT YELLOW (3175 2225);
FORCEPROP 1 LASTPIN (3175 2225) $PN 1
J 0
(3187 2237);
DISPLAY 0.787234 (3187 2237);
PAINT MONO (3187 2237);
FORCEPROP 1 LASTPIN (3375 2225) $PN 2
J 0
(3337 2237);
DISPLAY 0.787234 (3337 2237);
PAINT MONO (3337 2237);
FORCEPROP 0 LAST $SEC 1
J 0
(3175 2275);
DISPLAY 0.680851 (3175 2275);
PAINT MONO (3175 2275);
DISPLAY INVISIBLE (3175 2275);
FORCEPROP 0 LAST CDS_SEC 1
J 0
(3175 2275);
DISPLAY 0.680851 (3175 2275);
DISPLAY INVISIBLE (3175 2275);
FORCEADD Q_RES..1
(3275 2125);
FORCEPROP 1 LAST MATERIAL CHIP
J 2
(3650 2125);
DISPLAY 0.510638 (3650 2125);
PAINT SKYBLUE (3650 2125);
FORCEPROP 1 LAST VALUE 33.2
J 0
(3400 2125);
DISPLAY 0.510638 (3400 2125);
PAINT SKYBLUE (3400 2125);
FORCEPROP 1 LAST PACK_TYPE 0402LF
J 0
(3525 1975);
DISPLAY 0.510638 (3525 1975);
PAINT SKYBLUE (3525 1975);
DISPLAY INVISIBLE (3525 1975);
FORCEPROP 1 LAST WATTAGE 1/16W
J 2
(3250 1975);
DISPLAY 0.510638 (3250 1975);
PAINT SKYBLUE (3250 1975);
DISPLAY INVISIBLE (3250 1975);
FORCEPROP 1 LAST PART_NUMBER CS03322FB03
J 0
(3225 2225);
DISPLAY 0.510638 (3225 2225);
PAINT WHITE (3225 2225);
DISPLAY INVISIBLE (3225 2225);
FORCEPROP 1 LAST TOLERANCE 1%
J 0
(3400 2125);
DISPLAY 0.510638 (3400 2125);
PAINT SKYBLUE (3400 2125);
DISPLAY INVISIBLE (3400 2125);
FORCEPROP 1 LAST PATH I184
J 0
(3225 2275);
DISPLAY 0.978723 (3225 2275);
PAINT WHITE (3225 2275);
DISPLAY INVISIBLE (3225 2275);
FORCEPROP 2 LAST CDS_LIB pure_quanta
J 0
(3275 2125);
DISPLAY INVISIBLE (3275 2125);
FORCEPROP 1 LAST LOCATION R302
J 2
(3175 2125);
DISPLAY 0.702128 (3175 2125);
PAINT YELLOW (3175 2125);
FORCEPROP 1 LASTPIN (3175 2125) $PN 1
J 0
(3187 2137);
DISPLAY 0.787234 (3187 2137);
PAINT MONO (3187 2137);
FORCEPROP 1 LASTPIN (3375 2125) $PN 2
J 0
(3337 2137);
DISPLAY 0.787234 (3337 2137);
PAINT MONO (3337 2137);
FORCEPROP 0 LAST $SEC 1
J 0
(3175 2175);
DISPLAY 0.680851 (3175 2175);
PAINT MONO (3175 2175);
DISPLAY INVISIBLE (3175 2175);
FORCEPROP 0 LAST CDS_SEC 1
J 0
(3175 2175);
DISPLAY 0.680851 (3175 2175);
DISPLAY INVISIBLE (3175 2175);
FORCEADD Q_RES..1
(1250 1250);
FORCEPROP 1 LAST VALUE 100
J 0
(1350 1250);
DISPLAY 0.510638 (1350 1250);
PAINT SKYBLUE (1350 1250);
FORCEPROP 1 LAST PART_NUMBER CS11002FB07
J 0
(1000 1200);
DISPLAY 0.510638 (1000 1200);
PAINT WHITE (1000 1200);
FORCEPROP 1 LAST MATERIAL CHIP
J 0
(1450 1250);
DISPLAY 0.510638 (1450 1250);
PAINT SKYBLUE (1450 1250);
FORCEPROP 1 LAST WATTAGE 1/16W
J 2
(900 1150);
DISPLAY 0.510638 (900 1150);
PAINT SKYBLUE (900 1150);
DISPLAY INVISIBLE (900 1150);
FORCEPROP 1 LAST TOLERANCE 1%
J 0
(1275 1150);
DISPLAY 0.510638 (1275 1150);
PAINT SKYBLUE (1275 1150);
DISPLAY INVISIBLE (1275 1150);
FORCEPROP 1 LAST PACK_TYPE 0402LF
J 0
(1075 1150);
DISPLAY 0.510638 (1075 1150);
PAINT SKYBLUE (1075 1150);
DISPLAY INVISIBLE (1075 1150);
FORCEPROP 1 LAST PATH I185
J 0
(1200 1400);
DISPLAY 0.978723 (1200 1400);
PAINT WHITE (1200 1400);
DISPLAY INVISIBLE (1200 1400);
FORCEPROP 2 LAST CDS_LIB pure_quanta
J 0
(1250 1250);
DISPLAY INVISIBLE (1250 1250);
FORCEPROP 1 LAST LOCATION R384
J 0
(1050 1250);
DISPLAY 0.702128 (1050 1250);
PAINT YELLOW (1050 1250);
FORCEPROP 1 LASTPIN (1150 1250) $PN 1
J 0
(1162 1262);
DISPLAY 0.787234 (1162 1262);
PAINT MONO (1162 1262);
FORCEPROP 1 LASTPIN (1350 1250) $PN 2
J 0
(1312 1262);
DISPLAY 0.787234 (1312 1262);
PAINT MONO (1312 1262);
FORCEPROP 0 LAST $SEC 1
J 0
(1050 1300);
DISPLAY 0.680851 (1050 1300);
PAINT MONO (1050 1300);
DISPLAY INVISIBLE (1050 1300);
FORCEPROP 0 LAST CDS_SEC 1
J 0
(1050 1300);
DISPLAY 0.680851 (1050 1300);
DISPLAY INVISIBLE (1050 1300);
FORCEADD Q_CAP..1
(1400 600);
FORCEPROP 1 LAST VALUE 470PF
J 0
(1450 650);
DISPLAY 0.510638 (1450 650);
PAINT SKYBLUE (1450 650);
FORCEPROP 1 LAST VOLTAGE 50V
J 0
(1450 600);
DISPLAY 0.510638 (1450 600);
PAINT SKYBLUE (1450 600);
FORCEPROP 1 LAST TOLERANCE 10%
J 0
(1450 550);
DISPLAY 0.510638 (1450 550);
PAINT SKYBLUE (1450 550);
FORCEPROP 1 LAST MATERIAL X7R
J 0
(1450 500);
DISPLAY 0.510638 (1450 500);
PAINT SKYBLUE (1450 500);
FORCEPROP 1 LAST PACK_TYPE 0402
J 0
(1450 450);
DISPLAY 0.510638 (1450 450);
PAINT SKYBLUE (1450 450);
FORCEPROP 1 LAST PART_NUMBER TMP_QCH14706KB18
J 0
(1450 450);
DISPLAY 0.510638 (1450 450);
PAINT WHITE (1450 450);
DISPLAY INVISIBLE (1450 450);
FORCEPROP 2 LAST CDS_LIB pure_quanta
J 0
(1400 600);
PAINT RED (1400 600);
DISPLAY INVISIBLE (1400 600);
FORCEPROP 1 LAST PATH I35
J 0
(1450 750);
DISPLAY 0.978723 (1450 750);
PAINT WHITE (1450 750);
DISPLAY INVISIBLE (1450 750);
FORCEPROP 1 LAST LOCATION C172
J 0
(1450 700);
DISPLAY 0.702128 (1450 700);
PAINT YELLOW (1450 700);
FORCEPROP 1 LASTPIN (1400 700) $PN 1
J 0
(1410 680);
DISPLAY 0.808511 (1410 680);
PAINT WHITE (1410 680);
FORCEPROP 1 LASTPIN (1400 500) $PN 2
J 0
(1410 480);
DISPLAY 0.808511 (1410 480);
PAINT WHITE (1410 480);
FORCEPROP 2 LAST $SEC 1
J 0
(1450 800);
DISPLAY 0.680851 (1450 800);
PAINT MONO (1450 800);
DISPLAY INVISIBLE (1450 800);
FORCEPROP 2 LAST CDS_SEC 1
J 0
(1450 800);
DISPLAY 1.021277 (1450 800);
DISPLAY INVISIBLE (1450 800);
FORCEADD UNIVERSAL_GND..1
(1400 275);
FORCEPROP 3 LASTPIN (1400 325) SIG_NAME GND\g
J 0
(1410 335);
DISPLAY 0.659574 (1410 335);
PAINT MONO (1410 335);
DISPLAY INVISIBLE (1410 335);
FORCEPROP 1 LAST HDL_POWER GND
J 1
(1425 200);
DISPLAY 0.702128 (1425 200);
PAINT GREEN (1425 200);
FORCEPROP 2 LAST CDS_LIB logical_power
J 0
(1400 275);
DISPLAY INVISIBLE (1400 275);
FORCEPROP 1 LAST PATH I36
J 0
(1475 275);
DISPLAY 0.872340 (1475 275);
PAINT AQUA (1475 275);
DISPLAY INVISIBLE (1475 275);
FORCEADD UNIVERSAL_POWER..1
(800 875);
FORCEPROP 3 LASTPIN (800 825) SIG_NAME P5V_AUX\g
J 0
(810 835);
DISPLAY 0.659574 (810 835);
PAINT MONO (810 835);
DISPLAY INVISIBLE (810 835);
FORCEPROP 1 LAST HDL_POWER P5V_AUX
J 1
(800 925);
DISPLAY 0.702128 (800 925);
PAINT RED (800 925);
FORCEPROP 2 LAST CDS_LIB logical_power
J 0
(800 875);
PAINT RED (800 875);
DISPLAY INVISIBLE (800 875);
FORCEPROP 1 LAST PATH I37
J 0
(850 900);
DISPLAY 0.872340 (850 900);
PAINT AQUA (850 900);
DISPLAY INVISIBLE (850 900);
FORCEADD Q_CAP..1
(800 600);
FORCEPROP 1 LAST PART_NUMBER CH6222MEA00
J 0
(850 450);
DISPLAY 0.510638 (850 450);
PAINT WHITE (850 450);
FORCEPROP 1 LAST PACK_TYPE C0805
J 0
(850 400);
DISPLAY 0.510638 (850 400);
PAINT SKYBLUE (850 400);
FORCEPROP 1 LAST MATERIAL X6S
J 0
(850 500);
DISPLAY 0.510638 (850 500);
PAINT SKYBLUE (850 500);
FORCEPROP 1 LAST TOLERANCE 20%
J 0
(850 550);
DISPLAY 0.510638 (850 550);
PAINT SKYBLUE (850 550);
FORCEPROP 1 LAST VOLTAGE 10V
J 0
(850 600);
DISPLAY 0.510638 (850 600);
PAINT SKYBLUE (850 600);
FORCEPROP 1 LAST VALUE 22UF
J 0
(850 650);
DISPLAY 0.510638 (850 650);
PAINT SKYBLUE (850 650);
FORCEPROP 2 LAST CDS_LIB pure_quanta
J 0
(800 600);
DISPLAY INVISIBLE (800 600);
FORCEPROP 1 LAST PATH I38
J 0
(850 750);
DISPLAY 0.978723 (850 750);
PAINT WHITE (850 750);
DISPLAY INVISIBLE (850 750);
FORCEPROP 1 LAST LOCATION C171
J 0
(850 700);
DISPLAY 0.702128 (850 700);
PAINT YELLOW (850 700);
FORCEPROP 1 LASTPIN (800 700) $PN 1
J 0
(810 680);
DISPLAY 0.808511 (810 680);
PAINT WHITE (810 680);
FORCEPROP 1 LASTPIN (800 500) $PN 2
J 0
(810 480);
DISPLAY 0.808511 (810 480);
PAINT WHITE (810 480);
FORCEPROP 0 LAST $SEC 1
J 0
(850 750);
DISPLAY 0.680851 (850 750);
PAINT MONO (850 750);
DISPLAY INVISIBLE (850 750);
FORCEPROP 2 LAST CDS_SEC 1
J 0
(850 800);
DISPLAY 0.680851 (850 800);
DISPLAY INVISIBLE (850 800);
FORCEADD OFFPAGE..2
(2300 1250);
FORCEPROP 2 LAST $XR1 35 
J 0
(2579 1250);
DISPLAY 0.638298 (2579 1250);
PAINT MONO (2579 1250);
FORCEPROP 2 LAST $XR0 15 
J 0
(2489 1250);
DISPLAY 0.638298 (2489 1250);
PAINT MONO (2489 1250);
FORCEPROP 2 LAST PATH I39
J 0
(2500 1300);
DISPLAY 1.021277 (2500 1300);
DISPLAY INVISIBLE (2500 1300);
FORCEPROP 1 LAST COMMENT_BODY TRUE
J 0
(2255 1155);
DISPLAY 0.872340 (2255 1155);
PAINT PEACH (2255 1155);
DISPLAY INVISIBLE (2255 1155);
FORCEPROP 1 LAST OFFPAGE TRUE
J 0
(2625 1125);
DISPLAY 0.872340 (2625 1125);
PAINT GREEN (2625 1125);
DISPLAY INVISIBLE (2625 1125);
FORCEPROP 2 LAST CDS_LIB standard
J 0
(2300 1250);
DISPLAY INVISIBLE (2300 1250);
FORCEADD UNIVERSAL_POWER..1
(950 1700);
FORCEPROP 3 LASTPIN (950 1650) SIG_NAME P3V3_AUX\g
J 0
(960 1660);
DISPLAY 0.659574 (960 1660);
PAINT MONO (960 1660);
DISPLAY INVISIBLE (960 1660);
FORCEPROP 1 LAST HDL_POWER P3V3_AUX
J 1
(950 1750);
DISPLAY 0.702128 (950 1750);
PAINT PEACH (950 1750);
FORCEPROP 2 LAST CDS_LIB logical_power
J 0
(950 1700);
DISPLAY INVISIBLE (950 1700);
FORCEPROP 1 LAST PATH I40
J 0
(1000 1725);
DISPLAY 0.872340 (1000 1725);
PAINT AQUA (1000 1725);
DISPLAY INVISIBLE (1000 1725);
FORCEADD Q_RES..2
(950 1525);
FORCEPROP 1 LAST PACK_TYPE 0402LF
J 0
(990 1350);
DISPLAY 0.510638 (990 1350);
PAINT SKYBLUE (990 1350);
FORCEPROP 1 LAST PART_NUMBER CS31002FB08
J 0
(990 1400);
DISPLAY 0.510638 (990 1400);
PAINT WHITE (990 1400);
FORCEPROP 1 LAST MATERIAL CHIP
J 0
(990 1450);
DISPLAY 0.510638 (990 1450);
PAINT SKYBLUE (990 1450);
FORCEPROP 1 LAST VALUE 10K
J 0
(995 1600);
DISPLAY 0.510638 (995 1600);
PAINT SKYBLUE (995 1600);
FORCEPROP 1 LAST WATTAGE 1/16W
J 0
(990 1500);
DISPLAY 0.510638 (990 1500);
PAINT SKYBLUE (990 1500);
FORCEPROP 1 LAST TOLERANCE 1%
J 0
(995 1550);
DISPLAY 0.510638 (995 1550);
PAINT SKYBLUE (995 1550);
FORCEPROP 1 LAST PATH I42
J 0
(1000 1700);
DISPLAY 0.978723 (1000 1700);
PAINT WHITE (1000 1700);
DISPLAY INVISIBLE (1000 1700);
FORCEPROP 2 LAST CDS_LIB pure_quanta
J 0
(950 1525);
DISPLAY INVISIBLE (950 1525);
FORCEPROP 1 LAST LOCATION R383
J 0
(995 1650);
DISPLAY 0.702128 (995 1650);
PAINT YELLOW (995 1650);
FORCEPROP 0 LAST $SEC 1
J 0
(1000 1700);
DISPLAY 0.680851 (1000 1700);
PAINT MONO (1000 1700);
DISPLAY INVISIBLE (1000 1700);
FORCEPROP 0 LAST CDS_SEC 1
J 0
(1000 1700);
DISPLAY 1.021277 (1000 1700);
DISPLAY INVISIBLE (1000 1700);
FORCEPROP 1 LASTPIN (950 1625) $PN 1
J 0
(955 1587);
DISPLAY 0.808511 (955 1587);
PAINT WHITE (955 1587);
DISPLAY INVISIBLE (955 1587);
FORCEPROP 1 LASTPIN (950 1425) $PN 2
J 0
(955 1435);
DISPLAY 0.808511 (955 1435);
PAINT WHITE (955 1435);
DISPLAY INVISIBLE (955 1435);
FORCEADD UNIVERSAL_POWER..1
(625 1475);
FORCEPROP 3 LASTPIN (625 1425) SIG_NAME P5V_USB_REAR\g
J 0
(635 1435);
DISPLAY 0.659574 (635 1435);
PAINT MONO (635 1435);
DISPLAY INVISIBLE (635 1435);
FORCEPROP 1 LAST HDL_POWER P5V_USB_REAR
J 1
(625 1525);
DISPLAY 0.702128 (625 1525);
PAINT GREEN (625 1525);
FORCEPROP 2 LAST CDS_LIB logical_power
J 0
(625 1475);
DISPLAY INVISIBLE (625 1475);
FORCEPROP 1 LAST PATH I50
J 0
(675 1500);
DISPLAY 0.872340 (675 1500);
PAINT AQUA (675 1500);
DISPLAY INVISIBLE (675 1500);
FORCEADD UNIVERSAL_POWER..1
(-550 1475);
FORCEPROP 3 LASTPIN (-550 1425) SIG_NAME P5V_AUX\g
J 0
(-540 1435);
DISPLAY 0.659574 (-540 1435);
PAINT MONO (-540 1435);
DISPLAY INVISIBLE (-540 1435);
FORCEPROP 1 LAST HDL_POWER P5V_AUX
J 1
(-550 1525);
DISPLAY 0.702128 (-550 1525);
PAINT RED (-550 1525);
FORCEPROP 2 LAST CDS_LIB logical_power
J 0
(-550 1475);
DISPLAY INVISIBLE (-550 1475);
FORCEPROP 1 LAST PATH I52
J 0
(-500 1500);
DISPLAY 0.872340 (-500 1500);
PAINT AQUA (-500 1500);
DISPLAY INVISIBLE (-500 1500);
FORCEADD UNIVERSAL_GND..1
(-850 650);
FORCEPROP 3 LASTPIN (-850 700) SIG_NAME GND\g
J 0
(-840 710);
DISPLAY 0.659574 (-840 710);
PAINT MONO (-840 710);
DISPLAY INVISIBLE (-840 710);
FORCEPROP 1 LAST HDL_POWER GND
J 1
(-825 575);
DISPLAY 0.702128 (-825 575);
PAINT GREEN (-825 575);
FORCEPROP 2 LAST CDS_LIB logical_power
J 0
(-850 650);
DISPLAY INVISIBLE (-850 650);
FORCEPROP 1 LAST PATH I53
J 0
(-775 650);
DISPLAY 0.872340 (-775 650);
PAINT AQUA (-775 650);
DISPLAY INVISIBLE (-775 650);
FORCEADD Q_RES..2
(-1000 1000);
FORCEPROP 1 LAST VALUE 20K
J 0
(-955 1075);
DISPLAY 0.510638 (-955 1075);
PAINT SKYBLUE (-955 1075);
FORCEPROP 1 LAST TOLERANCE 1%
J 0
(-955 1025);
DISPLAY 0.510638 (-955 1025);
PAINT SKYBLUE (-955 1025);
FORCEPROP 1 LAST WATTAGE 1/16W
J 0
(-960 975);
DISPLAY 0.510638 (-960 975);
PAINT SKYBLUE (-960 975);
FORCEPROP 1 LAST MATERIAL CHIP
J 0
(-960 925);
DISPLAY 0.510638 (-960 925);
PAINT SKYBLUE (-960 925);
FORCEPROP 1 LAST PART_NUMBER CS32002FB06
J 0
(-960 875);
DISPLAY 0.510638 (-960 875);
PAINT WHITE (-960 875);
FORCEPROP 1 LAST PACK_TYPE 0402LF
J 0
(-960 825);
DISPLAY 0.510638 (-960 825);
PAINT SKYBLUE (-960 825);
FORCEPROP 1 LAST PATH I54
J 0
(-950 1175);
DISPLAY 0.978723 (-950 1175);
PAINT WHITE (-950 1175);
DISPLAY INVISIBLE (-950 1175);
FORCEPROP 2 LAST CDS_LIB pure_quanta
J 0
(-1000 1000);
DISPLAY INVISIBLE (-1000 1000);
FORCEPROP 1 LAST LOCATION R378
J 0
(-955 1125);
DISPLAY 0.702128 (-955 1125);
PAINT YELLOW (-955 1125);
FORCEPROP 0 LAST $SEC 1
J 0
(-950 1175);
DISPLAY 0.680851 (-950 1175);
PAINT MONO (-950 1175);
DISPLAY INVISIBLE (-950 1175);
FORCEPROP 0 LAST CDS_SEC 1
J 0
(-950 1175);
DISPLAY 1.021277 (-950 1175);
DISPLAY INVISIBLE (-950 1175);
FORCEPROP 1 LASTPIN (-1000 1100) $PN 1
J 0
(-995 1062);
DISPLAY 0.808511 (-995 1062);
PAINT WHITE (-995 1062);
DISPLAY INVISIBLE (-995 1062);
FORCEPROP 1 LASTPIN (-1000 900) $PN 2
J 0
(-995 910);
DISPLAY 0.808511 (-995 910);
PAINT WHITE (-995 910);
DISPLAY INVISIBLE (-995 910);
FORCEADD UNIVERSAL_POWER..1
(-1200 1600);
FORCEPROP 3 LASTPIN (-1200 1550) SIG_NAME P5V_AUX\g
J 0
(-1190 1560);
DISPLAY 0.659574 (-1190 1560);
PAINT MONO (-1190 1560);
DISPLAY INVISIBLE (-1190 1560);
FORCEPROP 1 LAST HDL_POWER P5V_AUX
J 1
(-1200 1650);
DISPLAY 0.702128 (-1200 1650);
PAINT RED (-1200 1650);
FORCEPROP 2 LAST CDS_LIB logical_power
J 0
(-1200 1600);
DISPLAY INVISIBLE (-1200 1600);
FORCEPROP 1 LAST PATH I61
J 0
(-1150 1625);
DISPLAY 0.872340 (-1150 1625);
PAINT AQUA (-1150 1625);
DISPLAY INVISIBLE (-1150 1625);
FORCEADD Q_RES..2
R 2
(-1200 1400);
FORCEPROP 1 LAST PART_NUMBER CS24702FB06
J 2
(-1240 1275);
DISPLAY 0.510638 (-1240 1275);
PAINT WHITE (-1240 1275);
FORCEPROP 1 LAST WATTAGE 1/16W
J 2
(-1240 1375);
DISPLAY 0.510638 (-1240 1375);
PAINT SKYBLUE (-1240 1375);
FORCEPROP 1 LAST TOLERANCE 1%
J 2
(-1245 1425);
DISPLAY 0.510638 (-1245 1425);
PAINT SKYBLUE (-1245 1425);
FORCEPROP 1 LAST VALUE 4.7K
J 2
(-1245 1475);
DISPLAY 0.510638 (-1245 1475);
PAINT SKYBLUE (-1245 1475);
FORCEPROP 1 LAST MATERIAL CHIP
J 2
(-1240 1325);
DISPLAY 0.510638 (-1240 1325);
PAINT SKYBLUE (-1240 1325);
FORCEPROP 1 LAST PACK_TYPE 0402LF
J 2
(-1240 1225);
DISPLAY 0.510638 (-1240 1225);
PAINT SKYBLUE (-1240 1225);
FORCEPROP 1 LAST PATH I62
J 2
(-1250 1575);
DISPLAY 0.978723 (-1250 1575);
PAINT WHITE (-1250 1575);
DISPLAY INVISIBLE (-1250 1575);
FORCEPROP 2 LAST CDS_LIB pure_quanta
J 0
(-1200 1400);
DISPLAY INVISIBLE (-1200 1400);
FORCEPROP 1 LAST LOCATION R376
J 2
(-1245 1525);
DISPLAY 0.702128 (-1245 1525);
PAINT YELLOW (-1245 1525);
FORCEPROP 0 LAST $SEC 1
J 0
(-1225 1575);
DISPLAY 0.680851 (-1225 1575);
PAINT MONO (-1225 1575);
DISPLAY INVISIBLE (-1225 1575);
FORCEPROP 0 LAST CDS_SEC 1
J 0
(-1225 1575);
DISPLAY 1.021277 (-1225 1575);
DISPLAY INVISIBLE (-1225 1575);
FORCEPROP 1 LASTPIN (-1200 1500) $PN 1
J 2
(-1205 1462);
DISPLAY 0.808511 (-1205 1462);
PAINT WHITE (-1205 1462);
DISPLAY INVISIBLE (-1205 1462);
FORCEPROP 1 LASTPIN (-1200 1300) $PN 2
J 2
(-1205 1310);
DISPLAY 0.808511 (-1205 1310);
PAINT WHITE (-1205 1310);
DISPLAY INVISIBLE (-1205 1310);
FORCEADD Q_RES..2
R 2
(-1200 925);
FORCEPROP 1 LAST WATTAGE 1/16W
J 2
(-1240 900);
DISPLAY 0.510638 (-1240 900);
PAINT SKYBLUE (-1240 900);
FORCEPROP 1 LAST VALUE 10K
J 2
(-1245 1000);
DISPLAY 0.510638 (-1245 1000);
PAINT SKYBLUE (-1245 1000);
FORCEPROP 1 LAST MATERIAL EMPTY
J 2
(-1240 850);
DISPLAY 0.510638 (-1240 850);
PAINT RED (-1240 850);
FORCEPROP 1 LAST TOLERANCE 1%
J 2
(-1245 950);
DISPLAY 0.510638 (-1245 950);
PAINT SKYBLUE (-1245 950);
FORCEPROP 1 LAST PACK_TYPE 0402LF
J 2
(-1240 750);
DISPLAY 0.510638 (-1240 750);
PAINT SKYBLUE (-1240 750);
FORCEPROP 1 LAST PART_NUMBER CS31002FB08
J 2
(-1240 800);
DISPLAY 0.510638 (-1240 800);
PAINT WHITE (-1240 800);
FORCEPROP 2 LAST CDS_LIB pure_quanta
J 0
(-1200 925);
DISPLAY INVISIBLE (-1200 925);
FORCEPROP 1 LAST PATH I63
J 2
(-1250 1100);
DISPLAY 0.978723 (-1250 1100);
PAINT WHITE (-1250 1100);
DISPLAY INVISIBLE (-1250 1100);
FORCEPROP 1 LAST LOCATION R377
J 2
(-1245 1050);
DISPLAY 0.702128 (-1245 1050);
PAINT YELLOW (-1245 1050);
FORCEPROP 0 LAST $SEC 1
J 0
(-1225 1100);
DISPLAY 0.680851 (-1225 1100);
PAINT MONO (-1225 1100);
DISPLAY INVISIBLE (-1225 1100);
FORCEPROP 0 LAST CDS_SEC 1
J 0
(-1225 1100);
DISPLAY 1.021277 (-1225 1100);
DISPLAY INVISIBLE (-1225 1100);
FORCEPROP 1 LASTPIN (-1200 1025) $PN 1
J 2
(-1205 987);
DISPLAY 0.808511 (-1205 987);
PAINT WHITE (-1205 987);
DISPLAY INVISIBLE (-1205 987);
FORCEPROP 1 LASTPIN (-1200 825) $PN 2
J 2
(-1205 835);
DISPLAY 0.808511 (-1205 835);
PAINT WHITE (-1205 835);
DISPLAY INVISIBLE (-1205 835);
FORCEADD UNIVERSAL_GND..1
(-1200 650);
FORCEPROP 3 LASTPIN (-1200 700) SIG_NAME GND\g
J 0
(-1190 710);
DISPLAY 0.659574 (-1190 710);
PAINT MONO (-1190 710);
DISPLAY INVISIBLE (-1190 710);
FORCEPROP 1 LAST HDL_POWER GND
J 1
(-1175 575);
DISPLAY 0.702128 (-1175 575);
PAINT GREEN (-1175 575);
FORCEPROP 2 LAST CDS_LIB logical_power
J 0
(-1200 650);
DISPLAY INVISIBLE (-1200 650);
FORCEPROP 1 LAST PATH I64
J 0
(-1125 650);
DISPLAY 0.872340 (-1125 650);
PAINT AQUA (-1125 650);
DISPLAY INVISIBLE (-1125 650);
FORCEADD VCCAUX15..1
(1650 3225);
FORCEPROP 3 LASTPIN (1650 3175) SIG_NAME P3V3_AUX\g
J 0
(1660 3185);
DISPLAY 0.659574 (1660 3185);
PAINT MONO (1660 3185);
DISPLAY INVISIBLE (1660 3185);
FORCEPROP 1 LAST HDL_POWER P3V3_AUX
J 1
(1650 3275);
DISPLAY 0.702128 (1650 3275);
PAINT GREEN (1650 3275);
FORCEPROP 2 LAST CDS_LIB logical_power
J 0
(1650 3225);
DISPLAY INVISIBLE (1650 3225);
FORCEPROP 1 LAST PATH I87
J 0
(1700 3250);
DISPLAY 0.872340 (1700 3250);
PAINT AQUA (1700 3250);
DISPLAY INVISIBLE (1700 3250);
FORCEADD VCCAUX15..1
(200 3075);
FORCEPROP 3 LASTPIN (200 3025) SIG_NAME P3V3_AUX\g
J 0
(210 3035);
DISPLAY 0.659574 (210 3035);
PAINT MONO (210 3035);
DISPLAY INVISIBLE (210 3035);
FORCEPROP 1 LAST HDL_POWER P3V3_AUX
J 1
(200 3125);
DISPLAY 0.702128 (200 3125);
PAINT GREEN (200 3125);
FORCEPROP 2 LAST CDS_LIB logical_power
J 0
(200 3075);
DISPLAY INVISIBLE (200 3075);
FORCEPROP 1 LAST PATH I88
J 0
(250 3100);
DISPLAY 0.872340 (250 3100);
PAINT AQUA (250 3100);
DISPLAY INVISIBLE (250 3100);
FORCEADD OFFPAGE..4
(4750 2225);
FORCEPROP 2 LAST $XR0 28 
J 0
(4936 2225);
DISPLAY 0.638298 (4936 2225);
PAINT MONO (4936 2225);
FORCEPROP 2 LAST $XR1 29 
J 0
(5026 2225);
DISPLAY 0.638298 (5026 2225);
PAINT MONO (5026 2225);
FORCEPROP 2 LAST PATH I89
J 0
(4950 2275);
DISPLAY 0.680851 (4950 2275);
DISPLAY INVISIBLE (4950 2275);
FORCEPROP 1 LAST COMMENT_BODY TRUE
J 0
(4725 2125);
DISPLAY 0.872340 (4725 2125);
PAINT GREEN (4725 2125);
DISPLAY INVISIBLE (4725 2125);
FORCEPROP 1 LAST OFFPAGE TRUE
J 0
(5075 2100);
DISPLAY 0.872340 (5075 2100);
DISPLAY INVISIBLE (5075 2100);
FORCEPROP 2 LAST CDS_LIB standard
J 0
(4750 2225);
DISPLAY INVISIBLE (4750 2225);
FORCEADD OFFPAGE..3
(4750 2125);
FORCEPROP 2 LAST $XR1 29 
J 0
(5054 2125);
DISPLAY 0.638298 (5054 2125);
PAINT MONO (5054 2125);
FORCEPROP 2 LAST $XR0 28 
J 0
(4964 2125);
DISPLAY 0.638298 (4964 2125);
PAINT MONO (4964 2125);
FORCEPROP 2 LAST PATH I90
J 0
(4975 2175);
DISPLAY 0.680851 (4975 2175);
DISPLAY INVISIBLE (4975 2175);
FORCEPROP 1 LAST COMMENT_BODY TRUE
J 0
(4700 2025);
DISPLAY 0.872340 (4700 2025);
PAINT PEACH (4700 2025);
DISPLAY INVISIBLE (4700 2025);
FORCEPROP 1 LAST OFFPAGE TRUE
J 0
(5075 2000);
DISPLAY 0.872340 (5075 2000);
PAINT GREEN (5075 2000);
DISPLAY INVISIBLE (5075 2000);
FORCEPROP 2 LAST CDS_LIB standard
J 0
(4750 2125);
DISPLAY INVISIBLE (4750 2125);
FORCEADD Q_RES..2
(3050 2675);
FORCEPROP 1 LAST VALUE 4.7K
J 0
(3095 2750);
DISPLAY 0.978723 (3095 2750);
FORCEPROP 1 LAST MATERIAL CHIP
J 0
(3090 2600);
DISPLAY 0.978723 (3090 2600);
FORCEPROP 1 LAST TOLERANCE 1%
J 0
(3095 2700);
DISPLAY 0.978723 (3095 2700);
FORCEPROP 1 LAST WATTAGE 1/16W
J 0
(3090 2650);
DISPLAY 0.978723 (3090 2650);
FORCEPROP 1 LAST PACK_TYPE 0402LF
J 0
(3090 2500);
DISPLAY 0.978723 (3090 2500);
FORCEPROP 1 LAST PART_NUMBER CS24702FB06
J 0
(3090 2550);
DISPLAY 0.978723 (3090 2550);
FORCEPROP 1 LAST PATH I91
J 0
(3100 2850);
DISPLAY 0.978723 (3100 2850);
PAINT WHITE (3100 2850);
DISPLAY INVISIBLE (3100 2850);
FORCEPROP 2 LAST CDS_LIB pure_quanta
J 0
(3050 2675);
DISPLAY INVISIBLE (3050 2675);
FORCEPROP 1 LAST LOCATION R299
J 0
(3095 2800);
DISPLAY 0.978723 (3095 2800);
FORCEPROP 1 LASTPIN (3050 2775) $PN 1
J 0
(3055 2737);
DISPLAY 0.787234 (3055 2737);
PAINT MONO (3055 2737);
FORCEPROP 1 LASTPIN (3050 2575) $PN 2
J 0
(3055 2585);
DISPLAY 0.787234 (3055 2585);
PAINT MONO (3055 2585);
FORCEPROP 0 LAST $SEC 1
J 0
(3100 2850);
DISPLAY 0.680851 (3100 2850);
PAINT MONO (3100 2850);
DISPLAY INVISIBLE (3100 2850);
FORCEPROP 0 LAST CDS_SEC 1
J 0
(3100 2850);
DISPLAY 0.680851 (3100 2850);
DISPLAY INVISIBLE (3100 2850);
FORCEADD OFFPAGE..1
R 2
(2350 1975);
FORCEPROP 2 LAST $XR0 28 
J 0
(2536 1975);
DISPLAY 0.638298 (2536 1975);
PAINT MONO (2536 1975);
FORCEPROP 2 LAST CDS_LIB standard
J 2
(2350 1975);
PAINT MONO (2350 1975);
DISPLAY INVISIBLE (2350 1975);
FORCEPROP 1 LAST OFFPAGE TRUE
J 2
(2025 1850);
DISPLAY 0.872340 (2025 1850);
DISPLAY INVISIBLE (2025 1850);
FORCEPROP 1 LAST COMMENT_BODY TRUE
J 2
(2225 1875);
DISPLAY 0.872340 (2225 1875);
PAINT GREEN (2225 1875);
DISPLAY INVISIBLE (2225 1875);
FORCEPROP 2 LAST PATH I94
J 0
(2550 2025);
DISPLAY 0.680851 (2550 2025);
DISPLAY INVISIBLE (2550 2025);
FORCEADD VCCAUX15..1
(2500 3275);
FORCEPROP 3 LASTPIN (2500 3225) SIG_NAME P3V3_AUX\g
J 0
(2510 3235);
DISPLAY 0.659574 (2510 3235);
PAINT MONO (2510 3235);
DISPLAY INVISIBLE (2510 3235);
FORCEPROP 1 LAST HDL_POWER P3V3_AUX
J 1
(2500 3325);
DISPLAY 0.702128 (2500 3325);
PAINT GREEN (2500 3325);
FORCEPROP 2 LAST CDS_LIB logical_power
J 0
(2500 3275);
DISPLAY INVISIBLE (2500 3275);
FORCEPROP 1 LAST PATH I95
J 0
(2550 3300);
DISPLAY 0.872340 (2550 3300);
PAINT AQUA (2550 3300);
DISPLAY INVISIBLE (2550 3300);
FORCEADD Q_RES..2
(2500 2675);
FORCEPROP 1 LAST PART_NUMBER CS24702FB06
J 0
(2540 2550);
DISPLAY 0.978723 (2540 2550);
FORCEPROP 1 LAST PACK_TYPE 0402LF
J 0
(2540 2500);
DISPLAY 0.978723 (2540 2500);
FORCEPROP 1 LAST VALUE 4.7K
J 0
(2545 2750);
DISPLAY 0.978723 (2545 2750);
FORCEPROP 1 LAST TOLERANCE 1%
J 0
(2545 2700);
DISPLAY 0.978723 (2545 2700);
FORCEPROP 1 LAST WATTAGE 1/16W
J 0
(2540 2650);
DISPLAY 0.978723 (2540 2650);
FORCEPROP 1 LAST MATERIAL CHIP
J 0
(2540 2600);
DISPLAY 0.978723 (2540 2600);
FORCEPROP 2 LAST CDS_LIB pure_quanta
J 0
(2500 2675);
DISPLAY INVISIBLE (2500 2675);
FORCEPROP 1 LAST PATH I96
J 0
(2550 2850);
DISPLAY 0.978723 (2550 2850);
PAINT WHITE (2550 2850);
DISPLAY INVISIBLE (2550 2850);
FORCEPROP 1 LAST LOCATION R298
J 0
(2545 2800);
DISPLAY 0.978723 (2545 2800);
FORCEPROP 1 LASTPIN (2500 2775) $PN 1
J 0
(2505 2737);
DISPLAY 0.787234 (2505 2737);
PAINT MONO (2505 2737);
FORCEPROP 1 LASTPIN (2500 2575) $PN 2
J 0
(2505 2585);
DISPLAY 0.787234 (2505 2585);
PAINT MONO (2505 2585);
FORCEPROP 0 LAST $SEC 1
J 0
(2550 2850);
DISPLAY 0.680851 (2550 2850);
PAINT MONO (2550 2850);
DISPLAY INVISIBLE (2550 2850);
FORCEPROP 0 LAST CDS_SEC 1
J 0
(2550 2850);
DISPLAY 0.680851 (2550 2850);
DISPLAY INVISIBLE (2550 2850);
FORCEADD UNIVERSAL_GND..1
(1400 2675);
FORCEPROP 3 LASTPIN (1400 2725) SIG_NAME GND\g
J 0
(1410 2735);
DISPLAY 0.659574 (1410 2735);
PAINT MONO (1410 2735);
DISPLAY INVISIBLE (1410 2735);
FORCEPROP 1 LAST HDL_POWER GND
J 1
(1425 2600);
DISPLAY 0.702128 (1425 2600);
PAINT GREEN (1425 2600);
FORCEPROP 2 LAST CDS_LIB logical_power
J 0
(1400 2675);
DISPLAY INVISIBLE (1400 2675);
FORCEPROP 1 LAST PATH I97
J 0
(1475 2675);
DISPLAY 0.872340 (1475 2675);
PAINT AQUA (1475 2675);
DISPLAY INVISIBLE (1475 2675);
FORCEADD Q_CAP..1
R 2
(1400 2925);
FORCEPROP 1 LAST MATERIAL X7R
J 2
(1350 2825);
DISPLAY 0.978723 (1350 2825);
FORCEPROP 1 LAST TOLERANCE 10%
J 2
(1350 2875);
DISPLAY 0.978723 (1350 2875);
FORCEPROP 1 LAST VALUE 0.1UF
J 2
(1350 2975);
DISPLAY 0.978723 (1350 2975);
FORCEPROP 1 LAST VOLTAGE 25V
J 2
(1350 2925);
DISPLAY 0.978723 (1350 2925);
FORCEPROP 1 LAST PACK_TYPE 0402
J 2
(1350 2725);
DISPLAY 0.978723 (1350 2725);
FORCEPROP 1 LAST PART_NUMBER CH4104K1B00
J 2
(1350 2775);
DISPLAY 0.978723 (1350 2775);
FORCEPROP 2 LAST CDS_LIB pure_quanta
J 2
(1400 2925);
DISPLAY INVISIBLE (1400 2925);
FORCEPROP 1 LAST PATH I98
J 2
(1350 3075);
DISPLAY 0.978723 (1350 3075);
PAINT WHITE (1350 3075);
DISPLAY INVISIBLE (1350 3075);
FORCEPROP 1 LAST LOCATION C159
J 2
(1350 3025);
DISPLAY 0.978723 (1350 3025);
FORCEPROP 1 LASTPIN (1400 3025) $PN 1
J 2
(1390 3005);
DISPLAY 0.787234 (1390 3005);
PAINT MONO (1390 3005);
FORCEPROP 1 LASTPIN (1400 2825) $PN 2
J 2
(1390 2805);
DISPLAY 0.787234 (1390 2805);
PAINT MONO (1390 2805);
FORCEPROP 2 LAST $SEC 1
J 0
(1350 3125);
DISPLAY 0.680851 (1350 3125);
PAINT MONO (1350 3125);
DISPLAY INVISIBLE (1350 3125);
FORCEPROP 2 LAST CDS_SEC 1
J 0
(1350 3125);
DISPLAY 1.021277 (1350 3125);
DISPLAY INVISIBLE (1350 3125);
FORCEADD PCA9517ADP..1
(825 2175);
FORCEPROP 2 LAST VALUE PCA9517ADP
J 0
(550 2700);
DISPLAY 1.021277 (550 2700);
FORCEPROP 2 LAST PACK_TYPE SMLF
J 0
(550 2650);
DISPLAY 1.021277 (550 2650);
FORCEPROP 1 LAST MATERIAL IC
J 0
(550 2500);
DISPLAY 0.723404 (550 2500);
PAINT GREEN (550 2500);
FORCEPROP 1 LAST PART_NUMBER AL009517K00
J 0
(550 2550);
DISPLAY 0.723404 (550 2550);
PAINT GREEN (550 2550);
FORCEPROP 1 LAST NEEDS_NO_SIZE TRUE
J 0
(825 2175);
DISPLAY 0.468085 (825 2175);
PAINT GREEN (825 2175);
DISPLAY INVISIBLE (825 2175);
FORCEPROP 2 LAST CDS_LIB pure_quanta
J 0
(825 2175);
DISPLAY INVISIBLE (825 2175);
FORCEPROP 1 LAST PATH I99
J 0
(1075 2500);
DISPLAY 0.723404 (1075 2500);
PAINT GREEN (1075 2500);
DISPLAY INVISIBLE (1075 2500);
FORCEPROP 1 LAST LOCATION U37
J 0
(550 2600);
DISPLAY 0.723404 (550 2600);
PAINT GREEN (550 2600);
FORCEPROP 0 LASTPIN (1250 1975) $PN 5
J 0
(1260 1985);
DISPLAY 0.680851 (1260 1985);
PAINT MONO (1260 1985);
FORCEPROP 0 LASTPIN (400 1975) $PN 4
J 2
(390 1985);
DISPLAY 0.680851 (390 1985);
PAINT MONO (390 1985);
FORCEPROP 0 LASTPIN (400 2225) $PN 2
J 2
(390 2235);
DISPLAY 0.680851 (390 2235);
PAINT MONO (390 2235);
FORCEPROP 0 LASTPIN (1250 2225) $PN 7
J 0
(1260 2235);
DISPLAY 0.680851 (1260 2235);
PAINT MONO (1260 2235);
FORCEPROP 0 LASTPIN (400 2125) $PN 3
J 2
(390 2135);
DISPLAY 0.680851 (390 2135);
PAINT MONO (390 2135);
FORCEPROP 0 LASTPIN (1250 2125) $PN 6
J 0
(1260 2135);
DISPLAY 0.680851 (1260 2135);
PAINT MONO (1260 2135);
FORCEPROP 0 LASTPIN (400 2375) $PN 1
J 2
(390 2385);
DISPLAY 0.680851 (390 2385);
PAINT MONO (390 2385);
FORCEPROP 0 LASTPIN (1250 2375) $PN 8
J 0
(1260 2385);
DISPLAY 0.680851 (1260 2385);
PAINT MONO (1260 2385);
FORCEPROP 0 LAST $SEC 1
J 0
(550 2750);
DISPLAY 0.680851 (550 2750);
PAINT MONO (550 2750);
DISPLAY INVISIBLE (550 2750);
FORCEPROP 0 LAST CDS_SEC 1
J 0
(550 2750);
DISPLAY 1.021277 (550 2750);
DISPLAY INVISIBLE (550 2750);
FORCEADD QUANTA_TITLE_BLOCK_C..1
(5150 -2250);
FORCEPROP 0 LAST CDS_CON_LAST_MODIFIED Fri Aug 25 17:25:41 2023
J 0
(3265 -2235);
DISPLAY INVISIBLE (3265 -2235);
FORCEPROP 2 LAST Q_DEPT 
J 1
(1387 -2201);
DISPLAY 1.957447 (1387 -2201);
PAINT GREEN (1387 -2201);
FORCEPROP 1 LAST CUSTOM_TXT_CDS <CON_LAST_MODIFIED>
J 0
(3265 -2235);
DISPLAY 0.978723 (3265 -2235);
FORCEPROP 2 LAST CUSTOM_TXT_CDS <XR_PAGE_TITLE>
J 0
(-2740 3000);
DISPLAY 0.638298 (-2740 3000);
PAINT PINK (-2740 3000);
DISPLAY INVISIBLE (-2740 3000);
FORCEPROP 1 LAST CUSTOM_TXT_CDS <NAME_2>
J 0
(1975 -2200);
FORCEPROP 1 LAST CUSTOM_TXT_CDS <NAME_1>
J 0
(1975 -2075);
FORCEPROP 1 LAST CUSTOM_TXT_CDS <Q_NUMBER>
J 0
(3747 -2147);
DISPLAY 1.212766 (3747 -2147);
FORCEPROP 1 LAST CUSTOM_TXT_CDS <Q_PROJ>
J 0
(2768 -2148);
DISPLAY 1.212766 (2768 -2148);
FORCEPROP 1 LAST CUSTOM_TXT_CDS <Q_REV>
J 0
(4966 -2147);
DISPLAY 1.212766 (4966 -2147);
FORCEPROP 1 LAST CUSTOM_TXT_CDS <CON_PAGE_NUM> OF <CON_TOTAL_PAGES>
J 0
(4704 -2232);
DISPLAY 0.978723 (4704 -2232);
FORCEPROP 1 LAST Q_TITLE USB - DEBUG CONNECTOR 1/2
J 0
(-4191 -2224);
DISPLAY 2.446809 (-4191 -2224);
PAINT GREEN (-4191 -2224);
FORCEPROP 2 LAST PAGE_BORDER TRUE
J 0
(-2740 3000);
DISPLAY 0.638298 (-2740 3000);
PAINT PINK (-2740 3000);
DISPLAY INVISIBLE (-2740 3000);
FORCEPROP 1 LAST CDS_LMAN_SYM_OUTLINE -9475,6775,100,-125
J 0
(5150 -2250);
DISPLAY 0.468085 (5150 -2250);
PAINT GREEN (5150 -2250);
DISPLAY INVISIBLE (5150 -2250);
FORCEPROP 2 LAST CDS_LIB pure_quanta
J 0
(5150 -2250);
DISPLAY INVISIBLE (5150 -2250);
FORCEPROP 1 LAST COMMENT_BODY TRUE
J 0
(5162 -2263);
DISPLAY 0.978723 (5162 -2263);
PAINT PEACH (5162 -2263);
DISPLAY INVISIBLE (5162 -2263);
FORCEPROP 2 LAST CDS_XR_PAGE_TITLE CR-28 : @SCM_LIB.SCM(SCH_1):PAGE28
J 0
(-2740 3000);
DISPLAY 0.638298 (-2740 3000);
PAINT PINK (-2740 3000);
DISPLAY INVISIBLE (-2740 3000);
FORCEADD DNS..1
(2025 -1375);
PAINT RED (2025 -1375);
FORCEPROP 2 LAST CDS_LIB mstr_misc
J 0
(2025 -1375);
DISPLAY INVISIBLE (2025 -1375);
FORCEPROP 1 LAST COMMENT_BODY TRUE
R 1
J 0
(2100 -1600);
DISPLAY 0.872340 (2100 -1600);
PAINT PEACH (2100 -1600);
DISPLAY INVISIBLE (2100 -1600);
FORCEADD DNS..1
(-975 3050);
PAINT RED (-975 3050);
FORCEPROP 2 LAST CDS_LIB mstr_misc
J 0
(-975 3050);
DISPLAY INVISIBLE (-975 3050);
FORCEPROP 1 LAST COMMENT_BODY TRUE
R 1
J 0
(-900 2825);
DISPLAY 0.872340 (-900 2825);
PAINT PEACH (-900 2825);
DISPLAY INVISIBLE (-900 2825);
FORCEADD DNS..1
(-1200 900);
PAINT RED (-1200 900);
FORCEPROP 2 LAST CDS_LIB mstr_misc
J 0
(-1200 900);
DISPLAY INVISIBLE (-1200 900);
FORCEPROP 1 LAST COMMENT_BODY TRUE
R 1
J 0
(-1125 675);
DISPLAY 0.872340 (-1125 675);
PAINT PEACH (-1125 675);
DISPLAY INVISIBLE (-1125 675);
FORCEADD DNS..1
(-3975 225);
PAINT RED (-3975 225);
FORCEPROP 2 LAST CDS_LIB mstr_misc
J 0
(-3975 225);
DISPLAY INVISIBLE (-3975 225);
FORCEPROP 1 LAST COMMENT_BODY TRUE
R 1
J 0
(-3900 0);
DISPLAY 0.872340 (-3900 0);
PAINT PEACH (-3900 0);
DISPLAY INVISIBLE (-3900 0);
FORCEADD DNS..1
(-3625 225);
PAINT RED (-3625 225);
FORCEPROP 2 LAST CDS_LIB mstr_misc
J 0
(-3625 225);
DISPLAY INVISIBLE (-3625 225);
FORCEPROP 1 LAST COMMENT_BODY TRUE
R 1
J 0
(-3550 0);
DISPLAY 0.872340 (-3550 0);
PAINT PEACH (-3550 0);
DISPLAY INVISIBLE (-3550 0);
FORCEADD DNS..1
(-3275 200);
PAINT RED (-3275 200);
FORCEPROP 2 LAST CDS_LIB mstr_misc
J 0
(-3275 200);
DISPLAY INVISIBLE (-3275 200);
FORCEPROP 1 LAST COMMENT_BODY TRUE
R 1
J 0
(-3200 -25);
DISPLAY 0.872340 (-3200 -25);
PAINT PEACH (-3200 -25);
DISPLAY INVISIBLE (-3200 -25);
WIRE 16 -1 (800 775)(800 825);
WIRE 16 -1 (800 775)(1400 775);
WIRE 16 -1 (800 700)(800 775);
WIRE 16 -1 (625 1300)(625 1425);
WIRE 16 -1 (325 1300)(625 1300);
WIRE 16 -1 (-1150 -75)(-1150 -150);
WIRE 16 -1 (-1775 -50)(-1775 -225);
WIRE 16 -1 (2475 125)(2475 -50);
WIRE 16 -1 (2500 3025)(2500 3225);
WIRE 16 -1 (2500 3025)(3050 3025);
WIRE 16 -1 (2500 2775)(2500 3025);
WIRE 16 -1 (-75 2600)(-75 2725);
WIRE 16 -1 (-950 2975)(-950 2775);
WIRE 16 -1 (-850 700)(-850 800);
WIRE 16 -1 (-1350 3900)(-1350 3975);
WIRE 16 -1 (-2125 4025)(-2125 3900);
WIRE 16 -1 (-2900 3375)(-2900 3150);
WIRE 16 -1 (-2725 3375)(-2900 3375);
WIRE 16 -1 (-3950 1200)(-3950 1300);
WIRE 16 -1 (-3950 1200)(-3600 1200);
WIRE 16 -1 (-3950 975)(-3950 1200);
WIRE 16 -1 (2725 975)(2725 800);
WIRE 16 -1 (-1200 825)(-1200 700);
WIRE 16 -1 (1400 2725)(1400 2825);
WIRE 16 -1 (-550 1425)(-550 1300);
WIRE 16 -1 (950 1625)(950 1650);
WIRE 16 -1 (1650 3175)(1650 3100);
WIRE 16 -1 (200 3025)(200 2925);
WIRE 16 -1 (-1975 3550)(-1975 3600);
WIRE 16 -1 (1400 375)(1400 325);
WIRE 16 -1 (1400 375)(1400 500);
WIRE 16 -1 (800 375)(1400 375);
WIRE 16 -1 (200 1975)(200 1875);
WIRE 16 -1 (400 1975)(200 1975);
WIRE 16 -1 (-1200 1550)(-1200 1500);
WIRE 16 -1 (4650 -850)(4650 -1125);
WIRE 16 -1 (4500 -850)(4650 -850);
WIRE 16 -1 (-1475 -400)(-1475 -500);
WIRE 16 -1 (-800 -675)(-1100 -675);
WIRE 16 -1 (-3800 -100)(-3800 -225);
WIRE 16 -1 (-3950 -100)(-3800 -100);
WIRE 16 -1 (-3800 -100)(-3600 -100);
WIRE 16 -1 (-550 1300)(-425 1300);
WIRE 16 273 (525 175)(1875 175);
WIRE 16 273 (1875 175)(1875 1075);
WIRE 16 273 (525 1075)(525 175);
WIRE 16 273 (525 1075)(1875 1075);
WIRE 16 -1 (1400 775)(1400 700);
WIRE 16 -1 (1350 1250)(2250 1250);
FORCEPROP 2 LAST SIG_NAME USB_OC0_REAR_R_N
J 2
(2240 1260);
DISPLAY 0.808511 (2240 1260);
WIRE 16 -1 (325 1250)(950 1250);
FORCEPROP 2 LAST SIG_NAME USB_OC0_REAR_N
J 2
(915 1260);
DISPLAY 0.808511 (915 1260);
WIRE 16 -1 (950 1250)(1150 1250);
WIRE 16 -1 (950 1425)(950 1250);
WIRE 16 -1 (3050 2575)(3050 2125);
WIRE 16 -1 (3175 2125)(3050 2125);
WIRE 16 -1 (1250 2125)(3050 2125);
FORCEPROP 2 LAST SIG_NAME SMB_DEBUG_AUX_LVC3_USB_R1_SDA
J 0
(1315 2135);
DISPLAY 0.851064 (1315 2135);
WIRE 16 -1 (2500 2575)(2500 2225);
WIRE 16 -1 (3175 2225)(2500 2225);
WIRE 16 -1 (1250 2225)(2500 2225);
FORCEPROP 2 LAST SIG_NAME SMB_DEBUG_AUX_LVC3_USB_R1_SCL
J 0
(1315 2235);
DISPLAY 0.851064 (1315 2235);
WIRE 16 -1 (3050 2775)(3050 3025);
WIRE 16 -1 (400 2125)(-1025 2125);
FORCEPROP 2 LAST SIG_NAME SMB_BMC_MM15_R1_SDA
J 0
(-660 2135);
DISPLAY 0.851064 (-660 2135);
WIRE 16 -1 (400 2225)(-1025 2225);
FORCEPROP 2 LAST SIG_NAME SMB_BMC_MM15_R1_SCL
J 0
(-660 2235);
DISPLAY 0.851064 (-660 2235);
WIRE 16 -1 (-1000 900)(-1000 800);
WIRE 16 -1 (-1000 800)(-850 800);
WIRE 16 -1 (375 800)(-850 800);
WIRE 16 -1 (375 1200)(375 800);
WIRE 16 -1 (325 1200)(375 1200);
WIRE 16 -1 (-1000 1200)(-1000 1100);
WIRE 16 -1 (-425 1200)(-1000 1200);
FORCEPROP 2 LAST SIG_NAME USB_OC0_ILIM
J 2
(-535 1210);
DISPLAY 0.808511 (-535 1210);
WIRE 16 -1 (-800 -775)(-1775 -775);
FORCEPROP 2 LAST SIG_NAME LED_POSTCODE_INT
J 0
(-1510 -765);
DISPLAY 0.851064 (-1510 -765);
WIRE 16 -1 (-1775 -425)(-1775 -775);
WIRE 16 -1 (-1475 -150)(-1475 -200);
WIRE 16 -1 (-1475 -150)(-1150 -150);
WIRE 16 -1 (-1150 -150)(-1150 -575);
WIRE 16 -1 (-1150 -575)(-800 -575);
WIRE 16 -1 (-1200 1300)(-1200 1250);
WIRE 16 -1 (-425 1250)(-1200 1250);
FORCEPROP 2 LAST SIG_NAME USB_OC0_EN
J 2
(-610 1260);
DISPLAY 0.808511 (-610 1260);
WIRE 16 -1 (-1200 1025)(-1200 1250);
WIRE 16 -1 (-800 -1225)(-2300 -1225);
FORCEPROP 2 LAST SIG_NAME SMB_DEBUG_AUX_LVC3_USB_R3_SDA
J 2
(-960 -1215);
DISPLAY 0.851064 (-960 -1215);
WIRE 16 -1 (-800 -1325)(-2300 -1325);
FORCEPROP 2 LAST SIG_NAME SMB_DEBUG_AUX_LVC3_USB_R3_SCL
J 2
(-960 -1315);
DISPLAY 0.851064 (-960 -1315);
WIRE 16 -1 (-3625 -1325)(-2500 -1325);
FORCEPROP 2 LAST SIG_NAME SMB_DEBUG_AUX_LVC3_USB_SCL
J 2
(-2560 -1315);
DISPLAY 0.851064 (-2560 -1315);
WIRE 16 -1 (1550 -1825)(1925 -1825);
WIRE 16 -1 (1550 -1325)(-50 -1325);
FORCEPROP 2 LAST SIG_NAME FM_SLPS3_GF_R2_N
J 0
(115 -1315);
DISPLAY 0.808511 (115 -1315);
WIRE 16 -1 (1550 -1325)(1550 -1825);
WIRE 16 -1 (1625 -1625)(1900 -1625);
WIRE 16 -1 (1625 -1275)(-50 -1275);
FORCEPROP 2 LAST SIG_NAME FM_CPU_MSMI_CATERR_LVT3_R3_N
J 0
(115 -1265);
DISPLAY 0.851064 (115 -1265);
WIRE 16 -1 (1625 -1275)(1625 -1625);
WIRE 16 -1 (2100 -1300)(3575 -1300);
FORCEPROP 2 LAST SIG_NAME PWRGD_PSU_AC_PWROK
J 0
(2790 -1290);
DISPLAY 0.808511 (2790 -1290);
WIRE 16 -1 (2100 -1625)(3575 -1625);
FORCEPROP 2 LAST SIG_NAME FM_CPU_MSMI_CATERR_LVT3_N
J 0
(2515 -1615);
DISPLAY 0.851064 (2515 -1615);
WIRE 16 -1 (2125 -1825)(3575 -1825);
FORCEPROP 2 LAST SIG_NAME FM_SLPS3_GF_N
J 0
(3015 -1815);
DISPLAY 0.808511 (3015 -1815);
WIRE 16 -1 (2100 -1225)(3575 -1225);
FORCEPROP 2 LAST SIG_NAME PWRGD_DSW_PWROK
J 0
(2790 -1215);
DISPLAY 0.851064 (2790 -1215);
WIRE 16 -1 (2100 -1175)(3575 -1175);
FORCEPROP 2 LAST SIG_NAME RST_PLTRST_N
J 0
(2790 -1165);
DISPLAY 0.851064 (2790 -1165);
WIRE 16 -1 (2100 -1125)(3575 -1125);
FORCEPROP 2 LAST SIG_NAME PWRGD_SYS_PWROK
J 0
(2790 -1115);
DISPLAY 0.851064 (2790 -1115);
WIRE 16 -1 (3600 -600)(2825 -600);
FORCEPROP 2 LAST SIG_NAME FM_UART_SEL_N
J 0
(2915 -590);
DISPLAY 0.851064 (2915 -590);
WIRE 16 -1 (2725 -350)(3600 -350);
WIRE 16 -1 (2725 600)(2725 300);
WIRE 16 -1 (2725 300)(3700 300);
FORCEPROP 2 LAST SIG_NAME FM_SOL_UART_CH_SEL_R3
J 0
(2765 310);
DISPLAY 0.851064 (2765 310);
WIRE 16 -1 (2725 300)(2725 -350);
WIRE 16 -1 (3900 300)(4725 300);
FORCEPROP 2 LAST SIG_NAME FM_SOL_UART_CH_SEL
J 0
(3940 310);
DISPLAY 0.851064 (3940 310);
WIRE 16 -1 (1250 1975)(2300 1975);
FORCEPROP 2 LAST SIG_NAME DEBUG_PORT_PRSNT_BUF_EN
J 0
(1315 1985);
DISPLAY 0.851064 (1315 1985);
WIRE 16 -1 (4700 2225)(3375 2225);
FORCEPROP 2 LAST SIG_NAME SMB_DEBUG_AUX_LVC3_USB_SCL
J 0
(3665 2235);
DISPLAY 0.851064 (3665 2235);
WIRE 16 -1 (4700 2125)(3375 2125);
FORCEPROP 2 LAST SIG_NAME SMB_DEBUG_AUX_LVC3_USB_SDA
J 0
(3665 2135);
DISPLAY 0.851064 (3665 2135);
WIRE 16 -1 (1400 3025)(1400 3100);
WIRE 16 -1 (1400 3100)(1650 3100);
WIRE 16 -1 (1650 3100)(1650 2375);
WIRE 16 -1 (1250 2375)(1650 2375);
WIRE 16 -1 (-75 2925)(200 2925);
WIRE 16 -1 (200 2925)(200 2375);
WIRE 16 -1 (400 2375)(200 2375);
WIRE 16 -1 (-2725 3475)(-3750 3475);
FORCEPROP 2 LAST SIG_NAME DEBUG_PORT_PRSNT
J 0
(-3610 3485);
DISPLAY 0.851064 (-3610 3485);
WIRE 16 -1 (1900 -1125)(-50 -1125);
FORCEPROP 2 LAST SIG_NAME PWRGD_SYS_PWROK_R1
J 0
(115 -1115);
DISPLAY 0.851064 (115 -1115);
WIRE 16 -1 (1900 -1175)(-50 -1175);
FORCEPROP 2 LAST SIG_NAME RST_PLTRST_R2_N
J 0
(115 -1165);
DISPLAY 0.851064 (115 -1165);
WIRE 16 -1 (-50 -1225)(1750 -1225);
FORCEPROP 2 LAST SIG_NAME PWRGD_DSW_PWROK_R3
J 0
(115 -1215);
DISPLAY 0.851064 (115 -1215);
WIRE 16 -1 (1900 -1225)(1750 -1225);
WIRE 16 -1 (1750 -1225)(1750 -1300);
WIRE 16 -1 (1750 -1300)(1900 -1300);
WIRE 16 -1 (2475 -600)(1725 -600);
WIRE 16 -1 (2475 -250)(2475 -600);
WIRE 16 -1 (2625 -600)(2475 -600);
FORCEPROP 2 LAST SIG_NAME FM_UART_SWITCH_N
J 2
(2365 -590);
DISPLAY 0.851064 (2365 -590);
WIRE 16 -1 (950 -1375)(-50 -1375);
FORCEPROP 2 LAST SIG_NAME FM_UART_SWITCH_N
J 0
(115 -1365);
DISPLAY 0.851064 (115 -1365);
WIRE 16 -1 (-50 3375)(900 3375);
FORCEPROP 2 LAST SIG_NAME DEBUG_PORT_PRSNT_BUF_EN
J 0
(-35 3385);
DISPLAY 0.851064 (-35 3385);
WIRE 16 -1 (800 500)(800 375);
WIRE 16 -1 (-3250 -100)(-3250 100);
WIRE 16 -1 (-3600 -100)(-3250 -100);
WIRE 16 -1 (-3600 100)(-3600 -100);
WIRE 16 -1 (-3950 100)(-3950 -100);
WIRE 16 -1 (-3250 975)(-3250 1200);
WIRE 16 -1 (-3600 1200)(-3250 1200);
WIRE 16 -1 (-3600 975)(-3600 1200);
WIRE 16 -1 (-2175 3575)(-2125 3575);
WIRE 16 -1 (-2125 3900)(-2125 3575);
WIRE 16 -1 (-2125 3900)(-1975 3900);
WIRE 16 -1 (-1975 3800)(-1975 3900);
WIRE 16 -1 (-950 3175)(-950 3375);
WIRE 16 -1 (-950 3375)(-250 3375);
WIRE 16 -1 (-1350 3700)(-1350 3375);
WIRE 16 -1 (-1350 3375)(-950 3375);
FORCEPROP 2 LAST SIG_NAME DEBUG_PORT_PRSNT_BUF_R_EN
J 0
(-1285 3385);
DISPLAY 0.851064 (-1285 3385);
WIRE 16 -1 (-2175 3375)(-1350 3375);
WIRE 16 -1 (-3250 300)(-3250 450);
WIRE 16 -1 (-3250 450)(-3250 775);
WIRE 16 -1 (-2225 450)(-3250 450);
FORCEPROP 2 LAST SIG_NAME LED_POSTCODE_A2
J 0
(-2935 460);
DISPLAY 0.808511 (-2935 460);
WIRE 16 -1 (-3950 550)(-3950 775);
WIRE 16 -1 (-3950 550)(-2225 550);
FORCEPROP 2 LAST SIG_NAME LED_POSTCODE_A0
J 0
(-2935 560);
DISPLAY 0.808511 (-2935 560);
WIRE 16 -1 (-3950 300)(-3950 550);
WIRE 16 -1 (-3600 500)(-3600 775);
WIRE 16 -1 (-3600 500)(-2225 500);
FORCEPROP 2 LAST SIG_NAME LED_POSTCODE_A1
J 0
(-2935 510);
DISPLAY 0.808511 (-2935 510);
WIRE 16 -1 (-3600 300)(-3600 500);
WIRE 16 -1 (-1225 2125)(-2250 2125);
FORCEPROP 2 LAST SIG_NAME SMB_BMC_MM15_SDA
J 0
(-2135 2135);
DISPLAY 0.851064 (-2135 2135);
WIRE 16 -1 (-3625 -1225)(-2500 -1225);
FORCEPROP 2 LAST SIG_NAME SMB_DEBUG_AUX_LVC3_USB_SDA
J 2
(-2560 -1215);
DISPLAY 0.851064 (-2560 -1215);
WIRE 16 -1 (950 -625)(-50 -625);
FORCEPROP 2 LAST SIG_NAME LED_POSTCODE_0_R1
J 0
(115 -615);
DISPLAY 0.808511 (115 -615);
WIRE 16 -1 (950 -925)(-50 -925);
FORCEPROP 2 LAST SIG_NAME LED_POSTCODE_6_R1
J 0
(115 -915);
DISPLAY 0.808511 (115 -915);
WIRE 16 -1 (950 -975)(-50 -975);
FORCEPROP 2 LAST SIG_NAME LED_POSTCODE_7_R1
J 0
(115 -965);
DISPLAY 0.808511 (115 -965);
WIRE 16 -1 (950 -1025)(-50 -1025);
FORCEPROP 2 LAST SIG_NAME FM_DEBUG_RST_BTN_N
J 0
(115 -1015);
DISPLAY 0.851064 (115 -1015);
WIRE 16 -1 (950 -675)(-50 -675);
FORCEPROP 2 LAST SIG_NAME LED_POSTCODE_1_R1
J 0
(115 -665);
DISPLAY 0.808511 (115 -665);
WIRE 16 -1 (-800 -925)(-1525 -925);
FORCEPROP 2 LAST SIG_NAME LED_POSTCODE_A1
J 0
(-1510 -915);
DISPLAY 0.808511 (-1510 -915);
WIRE 16 -1 (-800 -875)(-1525 -875);
FORCEPROP 2 LAST SIG_NAME LED_POSTCODE_A0
J 0
(-1510 -865);
DISPLAY 0.808511 (-1510 -865);
WIRE 16 -1 (-1225 2225)(-2250 2225);
FORCEPROP 2 LAST SIG_NAME SMB_BMC_MM15_SCL
J 0
(-2135 2260);
DISPLAY 0.851064 (-2135 2260);
WIRE 16 -1 (950 -725)(-50 -725);
FORCEPROP 2 LAST SIG_NAME LED_POSTCODE_2_R1
J 0
(115 -715);
DISPLAY 0.808511 (115 -715);
WIRE 16 -1 (950 -775)(-50 -775);
FORCEPROP 2 LAST SIG_NAME LED_POSTCODE_3_R1
J 0
(115 -765);
DISPLAY 0.808511 (115 -765);
WIRE 16 -1 (950 -825)(-50 -825);
FORCEPROP 2 LAST SIG_NAME LED_POSTCODE_4_R1
J 0
(115 -815);
DISPLAY 0.808511 (115 -815);
WIRE 16 -1 (950 -875)(-50 -875);
FORCEPROP 2 LAST SIG_NAME LED_POSTCODE_5_R1
J 0
(115 -865);
DISPLAY 0.808511 (115 -865);
WIRE 16 -1 (950 -1075)(-50 -1075);
FORCEPROP 2 LAST SIG_NAME FM_DEBUG_PWR_BTN_N
J 0
(115 -1065);
DISPLAY 0.851064 (115 -1065);
WIRE 16 -1 (-800 -975)(-1525 -975);
FORCEPROP 2 LAST SIG_NAME LED_POSTCODE_A2
J 0
(-1510 -965);
DISPLAY 0.808511 (-1510 -965);
DOT 1 (-1200 1250);
DOT 1 (1750 -1225);
DOT 1 (1400 375);
DOT 1 (800 775);
DOT 1 (2725 300);
DOT 1 (2475 -600);
DOT 1 (1650 3100);
DOT 1 (-3600 1200);
DOT 1 (-3950 1200);
DOT 1 (-3250 450);
DOT 1 (-3600 500);
DOT 1 (-3600 -100);
DOT 1 (-3950 550);
DOT 1 (-3800 -100);
DOT 1 (-950 3375);
DOT 1 (-1350 3375);
DOT 1 (-2125 3900);
DOT 1 (200 2925);
DOT 1 (2500 3025);
DOT 1 (2500 2225);
DOT 1 (3050 2125);
DOT 1 (-850 800);
DOT 1 (-1150 -150);
DOT 1 (950 1250);
FORCENOTE
CAD NOTE: PLACE AS CLOSE AS POSSIBLE TO TPS2553
(350 100) 0;
DISPLAY LEFT (350 100);
DISPLAY 0.808511 (350 100);
PAINT WHITE (350 100);
FORCENOTE
PCA9555 ADDRESS: 0X4E [0 1 0 0 A2 A1 A0 0]
(-3075 -1725) 0;
DISPLAY LEFT (-3075 -1725);
DISPLAY 1.595745 (-3075 -1725);
FORCENOTE
NOTE:PU ON BMC SIDE
(-2350 1950) 0;
DISPLAY LEFT (-2350 1950);
DISPLAY 2.000000 (-2350 1950);
QUIT
